(kicad_pcb
	(version 20260206)
	(generator "pcbnew")
	(generator_version "10.0")
	(general
		(thickness 1.5755)
		(legacy_teardrops no)
	)
	(paper "A4")
	(layers
		(0 "F.Cu" signal "L01-Top Layer")
		(4 "In1.Cu" signal "L02-Inner Layer")
		(6 "In2.Cu" signal "L03-Inner Layer")
		(2 "B.Cu" signal "L04-Bottom Layer")
		(9 "F.Adhes" user "F.Adhesive")
		(11 "B.Adhes" user "B.Adhesive")
		(13 "F.Paste" user "Top Paste")
		(15 "B.Paste" user "Bottom Paste")
		(5 "F.SilkS" user "Top Overlay")
		(7 "B.SilkS" user "Bottom Overlay")
		(1 "F.Mask" user "Top Solder")
		(3 "B.Mask" user "Bottom Solder")
		(17 "Dwgs.User" user "User.Drawings")
		(19 "Cmts.User" user "User.Comments")
		(21 "Eco1.User" user "User.Eco1")
		(23 "Eco2.User" user "User.Eco2")
		(25 "Edge.Cuts" user)
		(27 "Margin" user)
		(31 "F.CrtYd" user "Top Courtyard")
		(29 "B.CrtYd" user "Bottom Courtyard")
		(35 "F.Fab" user "Top Component Outline")
		(33 "B.Fab" user "Bottom Component Outline 2")
		(39 "User.1" user "M01_PCB_Outline")
	)
	(setup
		(pad_to_mask_clearance 0.05)
		(allow_soldermask_bridges_in_footprints no)
		(tenting
			(front yes)
			(back yes)
		)
		(covering
			(front no)
			(back no)
		)
		(plugging
			(front no)
			(back no)
		)
		(capping no)
		(filling no)
		(aux_axis_origin -9.7609 270.576095)
		(grid_origin -9.7609 270.576095)
		(pcbplotparams
			(layerselection 0x00000000_00000000_55555555_5755f5ff)
			(plot_on_all_layers_selection 0x00000000_00000000_00000000_00000000)
			(disableapertmacros no)
			(usegerberextensions no)
			(usegerberattributes yes)
			(usegerberadvancedattributes yes)
			(creategerberjobfile yes)
			(dashed_line_dash_ratio 12)
			(dashed_line_gap_ratio 3)
			(svgprecision 4)
			(plotframeref no)
			(mode 1)
			(useauxorigin no)
			(pdf_front_fp_property_popups yes)
			(pdf_back_fp_property_popups yes)
			(pdf_metadata yes)
			(pdf_single_document no)
			(dxfpolygonmode yes)
			(dxfimperialunits yes)
			(dxfusepcbnewfont yes)
			(psnegative no)
			(psa4output no)
			(plot_black_and_white yes)
			(sketchpadsonfab no)
			(plotpadnumbers no)
			(hidednponfab no)
			(sketchdnponfab yes)
			(crossoutdnponfab yes)
			(subtractmaskfromsilk no)
			(outputformat 1)
			(mirror no)
			(drillshape 1)
			(scaleselection 1)
			(outputdirectory "")
		)
	)
	(footprint "MyLibrary:led0603"
		(layer "F.Cu")
		(at 165.96429 110.401495 90)
		(property "Reference" "LED2"
			(at 3.4032 0.073243 90)
			(unlocked yes)
			(layer "F.SilkS")
			(effects
				(font
					(size 0.635 0.635)
					(thickness 0.1778)
				)
			)
		)
		(property "Value" "Green"
			(at -3.032583 3.262745 0)
			(unlocked yes)
			(layer "F.SilkS")
			(hide yes)
			(effects
				(font
					(size 0.635 0.635)
					(thickness 0.1778)
				)
			)
		)
		(sheetname "846-XXXXX_SCH_NEO-M9N_MODULE_2_RECEIVER")
		(sheetfile "846-XXXXX_SCH_NEO-M9N_MODULE_2_RECEIVER.kicad_sch")
		(duplicate_pad_numbers_are_jumpers no)
		(fp_line
			(start 1.397 -0.635)
			(end 1.397 0.635)
			(stroke
				(width 0.1778)
				(type solid)
			)
			(layer "F.SilkS")
		)
		(fp_line
			(start -1.397 -0.635)
			(end 1.397 -0.635)
			(stroke
				(width 0.1778)
				(type solid)
			)
			(layer "F.SilkS")
		)
		(fp_line
			(start -1.397 -0.635)
			(end -1.397 0.635)
			(stroke
				(width 0.1778)
				(type solid)
			)
			(layer "F.SilkS")
		)
		(fp_line
			(start -0.03175 -0.12065)
			(end 0.08255 -0.00635)
			(stroke
				(width 0.0762)
				(type solid)
			)
			(layer "F.SilkS")
		)
		(fp_line
			(start -0.03175 -0.12065)
			(end -0.03175 0.10795)
			(stroke
				(width 0.0762)
				(type solid)
			)
			(layer "F.SilkS")
		)
		(fp_line
			(start 0.08255 -0.00635)
			(end -0.03175 0.10795)
			(stroke
				(width 0.0762)
				(type solid)
			)
			(layer "F.SilkS")
		)
		(fp_line
			(start -1.397 0.635)
			(end 1.397 0.635)
			(stroke
				(width 0.1778)
				(type solid)
			)
			(layer "F.SilkS")
		)
		(fp_rect
			(start -0.032105 0.048195)
			(end 0.036975 -0.052755)
			(stroke
				(width 0)
				(type default)
			)
			(fill yes)
			(layer "F.SilkS")
		)
		(pad "1" smd rect
			(at -0.75 0 90)
			(size 0.8 0.8)
			(layers "F.Cu" "F.Mask" "F.Paste")
			(net "+3V3")
		)
		(pad "2" smd rect
			(at 0.75 0 90)
			(size 0.8 0.8)
			(layers "F.Cu" "F.Mask" "F.Paste")
			(net "NetLED2_2")
		)
	)
	(footprint "MyLibrary:TP1MM"
		(layer "F.Cu")
		(at 149.31461 97.161445)
		(property "Reference" "TP5"
			(at 0.022933 -1.763155 90)
			(unlocked yes)
			(layer "F.SilkS")
			(effects
				(font
					(size 0.635 0.635)
					(thickness 0.1778)
				)
			)
		)
		(property "Value" "1MM"
			(at -2.092783 1.790085 270)
			(unlocked yes)
			(layer "F.SilkS")
			(hide yes)
			(effects
				(font
					(size 0.635 0.635)
					(thickness 0.1778)
				)
			)
		)
		(sheetname "846-XXXXX_SCH_NEO-M9N_MODULE_2_RECEIVER")
		(sheetfile "846-XXXXX_SCH_NEO-M9N_MODULE_2_RECEIVER.kicad_sch")
		(duplicate_pad_numbers_are_jumpers no)
		(pad "1" smd circle
			(at 0 0)
			(size 1 1)
			(layers "F.Cu" "F.Mask" "F.Paste")
			(net "EXTIN")
			(solder_paste_margin -100)
			(thermal_bridge_angle 90)
		)
	)
	(footprint "MyLibrary:c0402"
		(layer "F.Cu")
		(at 153.21407 114.176095 90)
		(property "Reference" "C3"
			(at -3.083605 -0.122443 270)
			(unlocked yes)
			(layer "F.SilkS")
			(effects
				(font
					(size 0.635 0.635)
					(thickness 0.1778)
				)
			)
		)
		(property "Value" "10nF 50V 0402"
			(at 5.065455 2.118183 90)
			(unlocked yes)
			(layer "F.SilkS")
			(hide yes)
			(effects
				(font
					(size 0.635 0.635)
					(thickness 0.1778)
				)
			)
		)
		(sheetname "846-XXXXX_SCH_NEO-M9N_MODULE_2_RECEIVER")
		(sheetfile "846-XXXXX_SCH_NEO-M9N_MODULE_2_RECEIVER.kicad_sch")
		(duplicate_pad_numbers_are_jumpers no)
		(fp_line
			(start 0.9906 -0.4826)
			(end 0.9906 0.4826)
			(stroke
				(width 0.1778)
				(type solid)
			)
			(layer "F.SilkS")
		)
		(fp_line
			(start -0.9906 -0.4826)
			(end 0.9906 -0.4826)
			(stroke
				(width 0.1778)
				(type solid)
			)
			(layer "F.SilkS")
		)
		(fp_line
			(start -0.9906 -0.4826)
			(end -0.9906 0.4826)
			(stroke
				(width 0.1778)
				(type solid)
			)
			(layer "F.SilkS")
		)
		(fp_line
			(start -0.9906 0.4826)
			(end 0.9906 0.4826)
			(stroke
				(width 0.1778)
				(type solid)
			)
			(layer "F.SilkS")
		)
		(pad "1" smd rect
			(at -0.5 0 90)
			(size 0.5 0.5)
			(layers "F.Cu" "F.Mask" "F.Paste")
			(net "GND")
		)
		(pad "2" smd rect
			(at 0.5 0 90)
			(size 0.5 0.5)
			(layers "F.Cu" "F.Mask" "F.Paste")
			(net "+3V3")
		)
	)
	(footprint "MyLibrary:c0402"
		(layer "F.Cu")
		(at 139.71595 96.476095 -90)
		(property "Reference" "C4"
			(at -2.177805 -0.021583 90)
			(unlocked yes)
			(layer "F.SilkS")
			(effects
				(font
					(size 0.635 0.635)
					(thickness 0.1778)
				)
			)
		)
		(property "Value" "47pF 50V 0402"
			(at 5.192415 2.266303 270)
			(unlocked yes)
			(layer "F.SilkS")
			(hide yes)
			(effects
				(font
					(size 0.635 0.635)
					(thickness 0.1778)
				)
			)
		)
		(sheetname "846-XXXXX_SCH_NEO-M9N_MODULE_2_RECEIVER")
		(sheetfile "846-XXXXX_SCH_NEO-M9N_MODULE_2_RECEIVER.kicad_sch")
		(duplicate_pad_numbers_are_jumpers no)
		(fp_line
			(start -0.9906 0.4826)
			(end -0.9906 -0.4826)
			(stroke
				(width 0.1778)
				(type solid)
			)
			(layer "F.SilkS")
		)
		(fp_line
			(start 0.9906 0.4826)
			(end -0.9906 0.4826)
			(stroke
				(width 0.1778)
				(type solid)
			)
			(layer "F.SilkS")
		)
		(fp_line
			(start 0.9906 0.4826)
			(end 0.9906 -0.4826)
			(stroke
				(width 0.1778)
				(type solid)
			)
			(layer "F.SilkS")
		)
		(fp_line
			(start 0.9906 -0.4826)
			(end -0.9906 -0.4826)
			(stroke
				(width 0.1778)
				(type solid)
			)
			(layer "F.SilkS")
		)
		(pad "1" smd rect
			(at -0.5 0 270)
			(size 0.5 0.5)
			(layers "F.Cu" "F.Mask" "F.Paste")
			(net "RF_ANT")
		)
		(pad "2" smd rect
			(at 0.5 0 270)
			(size 0.5 0.5)
			(layers "F.Cu" "F.Mask" "F.Paste")
			(net "RF_MODULE")
		)
	)
	(footprint "MyLibrary:CONN_NRPN042MAMS-RC"
		(locked yes)
		(layer "F.Cu")
		(at 178.26011 112.596105 180)
		(property "Reference" "J1"
			(at -1.332795 7.697577 0)
			(unlocked yes)
			(layer "F.SilkS")
			(effects
				(font
					(size 0.635 0.635)
					(thickness 0.1778)
				)
			)
		)
		(property "Value" "NRPN042MAMS-RC 2MM"
			(at 7.90874 8.595193 180)
			(unlocked yes)
			(layer "F.SilkS")
			(hide yes)
			(effects
				(font
					(size 0.635 0.635)
					(thickness 0.1778)
				)
			)
		)
		(sheetname "846-XXXXX_SCH_NEO-M9N_MODULE_2_RECEIVER")
		(sheetfile "846-XXXXX_SCH_NEO-M9N_MODULE_2_RECEIVER.kicad_sch")
		(duplicate_pad_numbers_are_jumpers no)
		(fp_line
			(start 6.301 6.768)
			(end -1.7526 6.768)
			(stroke
				(width 0.1778)
				(type solid)
			)
			(layer "F.SilkS")
		)
		(fp_line
			(start 6.301 -0.725)
			(end 6.301 6.768)
			(stroke
				(width 0.1778)
				(type solid)
			)
			(layer "F.SilkS")
		)
		(fp_line
			(start 6.301 -0.725)
			(end -1.7526 -0.725)
			(stroke
				(width 0.1778)
				(type solid)
			)
			(layer "F.SilkS")
		)
		(fp_line
			(start -1.7526 -0.725)
			(end -1.7526 6.768)
			(stroke
				(width 0.1778)
				(type solid)
			)
			(layer "F.SilkS")
		)
		(fp_rect
			(start -2.9464 0.5842)
			(end -1.778 -0.8128)
			(stroke
				(width 0)
				(type default)
			)
			(fill yes)
			(layer "F.SilkS")
		)
		(pad "1" smd rect
			(at 0 0 180)
			(size 2.95 1.02)
			(layers "F.Cu" "F.Mask" "F.Paste")
			(net "+5V")
		)
		(pad "2" smd rect
			(at 4.55 0 180)
			(size 2.95 1.02)
			(layers "F.Cu" "F.Mask" "F.Paste")
			(net "+3V3")
		)
		(pad "3" smd rect
			(at 0 2.00001 180)
			(size 2.95 1.02)
			(layers "F.Cu" "F.Mask" "F.Paste")
			(net "TX_GPS_CONN")
		)
		(pad "4" smd rect
			(at 4.55 2.00001 180)
			(size 2.95 1.02)
			(layers "F.Cu" "F.Mask" "F.Paste")
			(net "RST_GPS")
		)
		(pad "5" smd rect
			(at 0 4 180)
			(size 2.95 1.02)
			(layers "F.Cu" "F.Mask" "F.Paste")
			(net "RX_GPS_CONN")
		)
		(pad "6" smd rect
			(at 4.55 4 180)
			(size 2.95 1.02)
			(layers "F.Cu" "F.Mask" "F.Paste")
			(net "TP1")
		)
		(pad "7" smd rect
			(at 0 6.00001 180)
			(size 2.95 1.02)
			(layers "F.Cu" "F.Mask" "F.Paste")
		)
		(pad "8" smd rect
			(at 4.55 6.00001 180)
			(size 2.95 1.02)
			(layers "F.Cu" "F.Mask" "F.Paste")
			(net "GND")
		)
	)
	(footprint "MyLibrary:r0402"
		(layer "F.Cu")
		(at 128.0151 110.476095)
		(property "Reference" "R6"
			(at 0.577995 1.322443 0)
			(unlocked yes)
			(layer "F.SilkS")
			(effects
				(font
					(size 0.635 0.635)
					(thickness 0.178)
				)
			)
		)
		(property "Value" "0 ohm 0402"
			(at 6.79212 2.200402 0)
			(unlocked yes)
			(layer "F.SilkS")
			(hide yes)
			(effects
				(font
					(size 1.524 1.524)
					(thickness 0.254)
				)
			)
		)
		(sheetname "846-XXXXX_SCH_NEO-M9N_MODULE_2_RECEIVER")
		(sheetfile "846-XXXXX_SCH_NEO-M9N_MODULE_2_RECEIVER.kicad_sch")
		(duplicate_pad_numbers_are_jumpers no)
		(fp_line
			(start -0.9906 -0.5334)
			(end 0.9906 -0.5334)
			(stroke
				(width 0.1778)
				(type solid)
			)
			(layer "F.SilkS")
		)
		(fp_line
			(start -0.9906 0.5334)
			(end -0.9906 -0.5334)
			(stroke
				(width 0.1778)
				(type solid)
			)
			(layer "F.SilkS")
		)
		(fp_line
			(start -0.9906 0.5334)
			(end 0.9906 0.5334)
			(stroke
				(width 0.1778)
				(type solid)
			)
			(layer "F.SilkS")
		)
		(fp_line
			(start 0.9906 0.5334)
			(end 0.9906 -0.5334)
			(stroke
				(width 0.1778)
				(type solid)
			)
			(layer "F.SilkS")
		)
		(pad "1" smd rect
			(at -0.5 0)
			(size 0.5 0.6)
			(layers "F.Cu" "F.Mask" "F.Paste")
			(net "NetQ1_1")
		)
		(pad "2" smd rect
			(at 0.5 0)
			(size 0.5 0.6)
			(layers "F.Cu" "F.Mask" "F.Paste")
			(net "+5V")
		)
	)
	(footprint "MyLibrary:r0402"
		(layer "F.Cu")
		(at 137.5151 113.676095 180)
		(property "Reference" "R7"
			(at -0.577995 -1.222433 0)
			(unlocked yes)
			(layer "F.SilkS")
			(effects
				(font
					(size 0.635 0.635)
					(thickness 0.178)
				)
			)
		)
		(property "Value" "0 ohm 0402"
			(at 6.79212 2.200402 180)
			(unlocked yes)
			(layer "F.SilkS")
			(hide yes)
			(effects
				(font
					(size 1.524 1.524)
					(thickness 0.254)
				)
			)
		)
		(sheetname "846-XXXXX_SCH_NEO-M9N_MODULE_2_RECEIVER")
		(sheetfile "846-XXXXX_SCH_NEO-M9N_MODULE_2_RECEIVER.kicad_sch")
		(duplicate_pad_numbers_are_jumpers no)
		(fp_line
			(start 0.9906 0.5334)
			(end -0.9906 0.5334)
			(stroke
				(width 0.1778)
				(type solid)
			)
			(layer "F.SilkS")
		)
		(fp_line
			(start 0.9906 -0.5334)
			(end 0.9906 0.5334)
			(stroke
				(width 0.1778)
				(type solid)
			)
			(layer "F.SilkS")
		)
		(fp_line
			(start 0.9906 -0.5334)
			(end -0.9906 -0.5334)
			(stroke
				(width 0.1778)
				(type solid)
			)
			(layer "F.SilkS")
		)
		(fp_line
			(start -0.9906 -0.5334)
			(end -0.9906 0.5334)
			(stroke
				(width 0.1778)
				(type solid)
			)
			(layer "F.SilkS")
		)
		(pad "1" smd rect
			(at -0.5 0 180)
			(size 0.5 0.6)
			(layers "F.Cu" "F.Mask" "F.Paste")
			(net "LNA_EN")
		)
		(pad "2" smd rect
			(at 0.5 0 180)
			(size 0.5 0.6)
			(layers "F.Cu" "F.Mask" "F.Paste")
			(net "NetQ1_1")
		)
	)
	(footprint "MyLibrary:led0603"
		(layer "F.Cu")
		(at 159.0643 110.401495 90)
		(property "Reference" "LED1"
			(at 3.3032 0.173243 90)
			(unlocked yes)
			(layer "F.SilkS")
			(effects
				(font
					(size 0.635 0.635)
					(thickness 0.1778)
				)
			)
		)
		(property "Value" "Green"
			(at -3.032583 3.262745 0)
			(unlocked yes)
			(layer "F.SilkS")
			(hide yes)
			(effects
				(font
					(size 0.635 0.635)
					(thickness 0.1778)
				)
			)
		)
		(sheetname "846-XXXXX_SCH_NEO-M9N_MODULE_2_RECEIVER")
		(sheetfile "846-XXXXX_SCH_NEO-M9N_MODULE_2_RECEIVER.kicad_sch")
		(duplicate_pad_numbers_are_jumpers no)
		(fp_line
			(start 1.397 -0.635)
			(end 1.397 0.635)
			(stroke
				(width 0.1778)
				(type solid)
			)
			(layer "F.SilkS")
		)
		(fp_line
			(start -1.397 -0.635)
			(end 1.397 -0.635)
			(stroke
				(width 0.1778)
				(type solid)
			)
			(layer "F.SilkS")
		)
		(fp_line
			(start -1.397 -0.635)
			(end -1.397 0.635)
			(stroke
				(width 0.1778)
				(type solid)
			)
			(layer "F.SilkS")
		)
		(fp_line
			(start -0.03175 -0.12065)
			(end 0.08255 -0.00635)
			(stroke
				(width 0.0762)
				(type solid)
			)
			(layer "F.SilkS")
		)
		(fp_line
			(start -0.03175 -0.12065)
			(end -0.03175 0.10795)
			(stroke
				(width 0.0762)
				(type solid)
			)
			(layer "F.SilkS")
		)
		(fp_line
			(start 0.08255 -0.00635)
			(end -0.03175 0.10795)
			(stroke
				(width 0.0762)
				(type solid)
			)
			(layer "F.SilkS")
		)
		(fp_line
			(start -1.397 0.635)
			(end 1.397 0.635)
			(stroke
				(width 0.1778)
				(type solid)
			)
			(layer "F.SilkS")
		)
		(fp_rect
			(start -0.03211 0.0482)
			(end 0.03698 -0.05275)
			(stroke
				(width 0)
				(type default)
			)
			(fill yes)
			(layer "F.SilkS")
		)
		(pad "1" smd rect
			(at -0.75 0 90)
			(size 0.8 0.8)
			(layers "F.Cu" "F.Mask" "F.Paste")
			(net "+5V")
		)
		(pad "2" smd rect
			(at 0.75 0 90)
			(size 0.8 0.8)
			(layers "F.Cu" "F.Mask" "F.Paste")
			(net "NetLED1_2")
		)
	)
	(footprint "MyLibrary:r0402"
		(layer "F.Cu")
		(at 124.9151 110.476095 180)
		(property "Reference" "R9"
			(at 0.221995 -1.322443 0)
			(unlocked yes)
			(layer "F.SilkS")
			(effects
				(font
					(size 0.635 0.635)
					(thickness 0.178)
				)
			)
		)
		(property "Value" "0 ohm 0402"
			(at 6.79212 2.200402 180)
			(unlocked yes)
			(layer "F.SilkS")
			(hide yes)
			(effects
				(font
					(size 1.524 1.524)
					(thickness 0.254)
				)
			)
		)
		(sheetname "846-XXXXX_SCH_NEO-M9N_MODULE_2_RECEIVER")
		(sheetfile "846-XXXXX_SCH_NEO-M9N_MODULE_2_RECEIVER.kicad_sch")
		(duplicate_pad_numbers_are_jumpers no)
		(fp_line
			(start 0.9906 0.5334)
			(end -0.9906 0.5334)
			(stroke
				(width 0.1778)
				(type solid)
			)
			(layer "F.SilkS")
		)
		(fp_line
			(start 0.9906 -0.5334)
			(end 0.9906 0.5334)
			(stroke
				(width 0.1778)
				(type solid)
			)
			(layer "F.SilkS")
		)
		(fp_line
			(start 0.9906 -0.5334)
			(end -0.9906 -0.5334)
			(stroke
				(width 0.1778)
				(type solid)
			)
			(layer "F.SilkS")
		)
		(fp_line
			(start -0.9906 -0.5334)
			(end -0.9906 0.5334)
			(stroke
				(width 0.1778)
				(type solid)
			)
			(layer "F.SilkS")
		)
		(pad "1" smd rect
			(at -0.5 0 180)
			(size 0.5 0.6)
			(layers "F.Cu" "F.Mask" "F.Paste")
			(net "NetQ1_1")
		)
		(pad "2" smd rect
			(at 0.5 0 180)
			(size 0.5 0.6)
			(layers "F.Cu" "F.Mask" "F.Paste")
			(net "GND")
		)
	)
	(footprint "MyLibrary:CONN_131-3711-301"
		(locked yes)
		(layer "F.Cu")
		(at 120.70511 101.076085 -90)
		(property "Reference" "J2"
			(at -4.777547 -3.387785 0)
			(unlocked yes)
			(layer "F.SilkS")
			(effects
				(font
					(size 0.635 0.635)
					(thickness 0.1778)
				)
			)
		)
		(property "Value" "SMB_131-3711-301"
			(at 7.55288 12.885653 270)
			(unlocked yes)
			(layer "F.SilkS")
			(hide yes)
			(effects
				(font
					(size 0.635 0.635)
					(thickness 0.1778)
				)
			)
		)
		(sheetname "846-XXXXX_SCH_NEO-M9N_MODULE_2_RECEIVER")
		(sheetfile "846-XXXXX_SCH_NEO-M9N_MODULE_2_RECEIVER.kicad_sch")
		(duplicate_pad_numbers_are_jumpers no)
		(fp_line
			(start -3.8 3.8)
			(end -3.8 -3.8)
			(stroke
				(width 0.1778)
				(type solid)
			)
			(layer "F.SilkS")
		)
		(fp_line
			(start 3.8 3.8)
			(end -3.8 3.8)
			(stroke
				(width 0.1778)
				(type solid)
			)
			(layer "F.SilkS")
		)
		(fp_line
			(start 3.8 3.8)
			(end 3.8 -3.8)
			(stroke
				(width 0.1778)
				(type solid)
			)
			(layer "F.SilkS")
		)
		(fp_line
			(start 3.8 -3.8)
			(end -3.8 -3.8)
			(stroke
				(width 0.1778)
				(type solid)
			)
			(layer "F.SilkS")
		)
		(pad "" smd custom
			(at -3.58131 3.55583)
			(size 0.000001 0.000001)
			(layers "F.Cu" "F.Mask" "F.Paste")
			(solder_paste_margin -0.2)
			(thermal_bridge_angle 90)
			(options
				(clearance outline)
				(anchor circle)
			)
			(primitives
				(gr_poly
					(pts
						(xy 0 0) (xy 0 2.3622)
						(arc
							(start 1.914553 2.3622)
							(mid 3.556 1.5367)
							(end 5.197447 2.3622)
						)
						(xy 5.19745 2.3622) (xy 7.112 2.3622) (xy 7.112 0)
					)
					(width 0)
					(fill yes)
				)
			)
		)
		(pad "" smd custom
			(at -0.86351 -0.00017)
			(size 0.000001 0.000001)
			(layers "F.Cu" "F.Mask" "F.Paste")
			(solder_paste_margin -0.2)
			(thermal_bridge_angle 90)
			(options
				(clearance outline)
				(anchor circle)
			)
			(primitives
				(gr_poly
					(pts
						(arc
							(start 0 0)
							(mid -0.610657 0.252943)
							(end -0.8636 0.8636)
						)
						(arc
							(start -0.8636 0.8636)
							(mid -0.610657 1.474257)
							(end 0 1.7272)
						)
						(arc
							(start 0 1.7272)
							(mid 0.610657 1.474257)
							(end 0.8636 0.8636)
						)
						(arc
							(start 0.8636 0.8636)
							(mid 0.610657 0.252943)
							(end 0 0)
						)
					)
					(width 0)
					(fill yes)
				)
			)
		)
		(pad "" smd custom
			(at 1.21929 3.55583)
			(size 0.000001 0.000001)
			(layers "F.Cu" "F.Mask" "F.Paste")
			(solder_paste_margin -0.2)
			(thermal_bridge_angle 90)
			(options
				(clearance outline)
				(anchor circle)
			)
			(primitives
				(gr_poly
					(pts
						(xy 0 0) (xy 0 2.3622) (xy 7.112 2.3622) (xy 7.112 0)
						(arc
							(start 5.197447 0)
							(mid 3.556 0.8255)
							(end 1.914553 0)
						)
						(xy 1.91455 0)
					)
					(width 0)
					(fill yes)
				)
			)
		)
		(pad "1" smd circle
			(at 0.00009 -0.00017 270)
			(size 1 1)
			(layers "F.Cu" "F.Mask" "F.Paste")
			(net "RF_ANT")
			(solder_mask_margin 0)
			(thermal_bridge_angle 90)
		)
		(pad "2" smd rect
			(at -2.794 0.254 270)
			(size 1 5)
			(layers "F.Cu" "F.Mask" "F.Paste")
			(net "GND")
			(solder_mask_margin 0)
		)
		(pad "3" smd rect
			(at 2.91616 0 270)
			(size 1 5)
			(layers "F.Cu" "F.Mask" "F.Paste")
			(net "GND")
			(solder_mask_margin 0)
		)
	)
	(footprint "MyLibrary:TP1MM"
		(layer "F.Cu")
		(at 148.2151 95.576095)
		(property "Reference" "TP2"
			(at 0.122433 -1.677805 90)
			(unlocked yes)
			(layer "F.SilkS")
			(effects
				(font
					(size 0.635 0.635)
					(thickness 0.1778)
				)
			)
		)
		(property "Value" "1MM"
			(at -2.092793 1.790085 270)
			(unlocked yes)
			(layer "F.SilkS")
			(hide yes)
			(effects
				(font
					(size 0.635 0.635)
					(thickness 0.1778)
				)
			)
		)
		(sheetname "846-XXXXX_SCH_NEO-M9N_MODULE_2_RECEIVER")
		(sheetfile "846-XXXXX_SCH_NEO-M9N_MODULE_2_RECEIVER.kicad_sch")
		(duplicate_pad_numbers_are_jumpers no)
		(pad "1" smd circle
			(at 0 0)
			(size 1 1)
			(layers "F.Cu" "F.Mask" "F.Paste")
			(net "USB_DM")
			(solder_paste_margin -100)
			(thermal_bridge_angle 90)
		)
	)
	(footprint "MyLibrary:r0603"
		(layer "F.Cu")
		(at 125.9151 104.187745 90)
		(property "Reference" "R4"
			(at -0.910793 1.877795 0)
			(unlocked yes)
			(layer "F.SilkS")
			(effects
				(font
					(size 0.635 0.635)
					(thickness 0.1778)
				)
			)
		)
		(property "Value" "10 OHM 1/4W 0603"
			(at -5.216993 5.192245 0)
			(unlocked yes)
			(layer "F.SilkS")
			(hide yes)
			(effects
				(font
					(size 0.635 0.635)
					(thickness 0.1778)
				)
			)
		)
		(sheetname "846-XXXXX_SCH_NEO-M9N_MODULE_2_RECEIVER")
		(sheetfile "846-XXXXX_SCH_NEO-M9N_MODULE_2_RECEIVER.kicad_sch")
		(duplicate_pad_numbers_are_jumpers no)
		(fp_line
			(start 1.2954 -0.6858)
			(end 1.2954 0.6858)
			(stroke
				(width 0.1778)
				(type solid)
			)
			(layer "F.SilkS")
		)
		(fp_line
			(start -1.2954 -0.6858)
			(end 1.2954 -0.6858)
			(stroke
				(width 0.1778)
				(type solid)
			)
			(layer "F.SilkS")
		)
		(fp_line
			(start -1.2954 -0.6858)
			(end -1.2954 0.6858)
			(stroke
				(width 0.1778)
				(type solid)
			)
			(layer "F.SilkS")
		)
		(fp_line
			(start -1.2954 0.6858)
			(end 1.2954 0.6858)
			(stroke
				(width 0.1778)
				(type solid)
			)
			(layer "F.SilkS")
		)
		(pad "1" smd rect
			(at -0.75 0 90)
			(size 0.6 0.9)
			(layers "F.Cu" "F.Mask" "F.Paste")
			(net "NetQ1_3")
		)
		(pad "2" smd rect
			(at 0.75 0 90)
			(size 0.6 0.9)
			(layers "F.Cu" "F.Mask" "F.Paste")
			(net "NetC5_2")
		)
	)
	(footprint "MyLibrary:r0402"
		(layer "F.Cu")
		(at 160.8151 109.976095 90)
		(property "Reference" "R2"
			(at 2.477805 0.022443 90)
			(unlocked yes)
			(layer "F.SilkS")
			(effects
				(font
					(size 0.635 0.635)
					(thickness 0.1778)
				)
			)
		)
		(property "Value" "10K 1/8W 0402"
			(at 4.938495 2.168983 90)
			(unlocked yes)
			(layer "F.SilkS")
			(hide yes)
			(effects
				(font
					(size 0.635 0.635)
					(thickness 0.1778)
				)
			)
		)
		(sheetname "846-XXXXX_SCH_NEO-M9N_MODULE_2_RECEIVER")
		(sheetfile "846-XXXXX_SCH_NEO-M9N_MODULE_2_RECEIVER.kicad_sch")
		(duplicate_pad_numbers_are_jumpers no)
		(fp_line
			(start 0.9906 -0.5334)
			(end 0.9906 0.5334)
			(stroke
				(width 0.1778)
				(type solid)
			)
			(layer "F.SilkS")
		)
		(fp_line
			(start -0.9906 -0.5334)
			(end 0.9906 -0.5334)
			(stroke
				(width 0.1778)
				(type solid)
			)
			(layer "F.SilkS")
		)
		(fp_line
			(start -0.9906 -0.5334)
			(end -0.9906 0.5334)
			(stroke
				(width 0.1778)
				(type solid)
			)
			(layer "F.SilkS")
		)
		(fp_line
			(start -0.9906 0.5334)
			(end 0.9906 0.5334)
			(stroke
				(width 0.1778)
				(type solid)
			)
			(layer "F.SilkS")
		)
		(pad "1" smd rect
			(at -0.5 0 90)
			(size 0.5 0.6)
			(layers "F.Cu" "F.Mask" "F.Paste")
			(net "GND")
		)
		(pad "2" smd rect
			(at 0.5 0 90)
			(size 0.5 0.6)
			(layers "F.Cu" "F.Mask" "F.Paste")
			(net "NetLED1_2")
		)
	)
	(footprint "MyLibrary:TP1MM"
		(layer "F.Cu")
		(at 147.1151 113.676095)
		(property "Reference" "TP9"
			(at -0.022443 1.977805 270)
			(unlocked yes)
			(layer "F.SilkS")
			(effects
				(font
					(size 0.635 0.635)
					(thickness 0.1778)
				)
			)
		)
		(property "Value" "1MM"
			(at -2.092793 1.790085 270)
			(unlocked yes)
			(layer "F.SilkS")
			(hide yes)
			(effects
				(font
					(size 0.635 0.635)
					(thickness 0.1778)
				)
			)
		)
		(sheetname "846-XXXXX_SCH_NEO-M9N_MODULE_2_RECEIVER")
		(sheetfile "846-XXXXX_SCH_NEO-M9N_MODULE_2_RECEIVER.kicad_sch")
		(duplicate_pad_numbers_are_jumpers no)
		(pad "1" smd circle
			(at 0 0)
			(size 1 1)
			(layers "F.Cu" "F.Mask" "F.Paste")
			(net "SCL_SPI_CLK")
			(solder_paste_margin -100)
			(thermal_bridge_angle 90)
		)
	)
	(footprint "MyLibrary:TP1MM"
		(layer "F.Cu")
		(at 146.01515 95.576095)
		(property "Reference" "TP4"
			(at 0.122393 -1.677805 90)
			(unlocked yes)
			(layer "F.SilkS")
			(effects
				(font
					(size 0.635 0.635)
					(thickness 0.1778)
				)
			)
		)
		(property "Value" "1MM"
			(at -2.092793 1.790085 270)
			(unlocked yes)
			(layer "F.SilkS")
			(hide yes)
			(effects
				(font
					(size 0.635 0.635)
					(thickness 0.1778)
				)
			)
		)
		(sheetname "846-XXXXX_SCH_NEO-M9N_MODULE_2_RECEIVER")
		(sheetfile "846-XXXXX_SCH_NEO-M9N_MODULE_2_RECEIVER.kicad_sch")
		(duplicate_pad_numbers_are_jumpers no)
		(pad "1" smd circle
			(at 0 0)
			(size 1 1)
			(layers "F.Cu" "F.Mask" "F.Paste")
			(net "VDD_USB")
			(solder_paste_margin -100)
			(thermal_bridge_angle 90)
		)
	)
	(footprint "MyLibrary:c0402"
		(layer "F.Cu")
		(at 128.2151 103.437745 180)
		(property "Reference" "C5"
			(at -2.177795 -0.122443 0)
			(unlocked yes)
			(layer "F.SilkS")
			(effects
				(font
					(size 0.635 0.635)
					(thickness 0.1778)
				)
			)
		)
		(property "Value" "10nF 50V 0402"
			(at 5.065455 2.118183 180)
			(unlocked yes)
			(layer "F.SilkS")
			(hide yes)
			(effects
				(font
					(size 0.635 0.635)
					(thickness 0.1778)
				)
			)
		)
		(sheetname "846-XXXXX_SCH_NEO-M9N_MODULE_2_RECEIVER")
		(sheetfile "846-XXXXX_SCH_NEO-M9N_MODULE_2_RECEIVER.kicad_sch")
		(duplicate_pad_numbers_are_jumpers no)
		(fp_line
			(start 0.9906 0.4826)
			(end -0.9906 0.4826)
			(stroke
				(width 0.1778)
				(type solid)
			)
			(layer "F.SilkS")
		)
		(fp_line
			(start 0.9906 -0.4826)
			(end 0.9906 0.4826)
			(stroke
				(width 0.1778)
				(type solid)
			)
			(layer "F.SilkS")
		)
		(fp_line
			(start 0.9906 -0.4826)
			(end -0.9906 -0.4826)
			(stroke
				(width 0.1778)
				(type solid)
			)
			(layer "F.SilkS")
		)
		(fp_line
			(start -0.9906 -0.4826)
			(end -0.9906 0.4826)
			(stroke
				(width 0.1778)
				(type solid)
			)
			(layer "F.SilkS")
		)
		(pad "1" smd rect
			(at -0.5 0 180)
			(size 0.5 0.5)
			(layers "F.Cu" "F.Mask" "F.Paste")
			(net "GND")
		)
		(pad "2" smd rect
			(at 0.5 0 180)
			(size 0.5 0.5)
			(layers "F.Cu" "F.Mask" "F.Paste")
			(net "NetC5_2")
		)
	)
	(footprint "MyLibrary:r0402"
		(layer "F.Cu")
		(at 175.97619 101.376095 -90)
		(property "Reference" "R8"
			(at 1.622443 -0.116705 0)
			(unlocked yes)
			(layer "F.SilkS")
			(effects
				(font
					(size 0.635 0.635)
					(thickness 0.1778)
				)
			)
		)
		(property "Value" "0 ohm 0402"
			(at 2.907155 2.168983 270)
			(unlocked yes)
			(layer "F.SilkS")
			(hide yes)
			(effects
				(font
					(size 0.635 0.635)
					(thickness 0.1778)
				)
			)
		)
		(sheetname "846-XXXXX_SCH_NEO-M9N_MODULE_2_RECEIVER")
		(sheetfile "846-XXXXX_SCH_NEO-M9N_MODULE_2_RECEIVER.kicad_sch")
		(duplicate_pad_numbers_are_jumpers no)
		(fp_line
			(start -0.9906 0.5334)
			(end -0.9906 -0.5334)
			(stroke
				(width 0.1778)
				(type solid)
			)
			(layer "F.SilkS")
		)
		(fp_line
			(start 0.9906 0.5334)
			(end -0.9906 0.5334)
			(stroke
				(width 0.1778)
				(type solid)
			)
			(layer "F.SilkS")
		)
		(fp_line
			(start 0.9906 0.5334)
			(end 0.9906 -0.5334)
			(stroke
				(width 0.1778)
				(type solid)
			)
			(layer "F.SilkS")
		)
		(fp_line
			(start 0.9906 -0.5334)
			(end -0.9906 -0.5334)
			(stroke
				(width 0.1778)
				(type solid)
			)
			(layer "F.SilkS")
		)
		(pad "1" smd rect
			(at -0.5 0 270)
			(size 0.5 0.6)
			(layers "F.Cu" "F.Mask" "F.Paste")
			(net "TX_GPS")
		)
		(pad "2" smd rect
			(at 0.5 0 270)
			(size 0.5 0.6)
			(layers "F.Cu" "F.Mask" "F.Paste")
			(net "TX_GPS_CONN")
		)
	)
	(footprint "MyLibrary:TP1MM"
		(layer "F.Cu")
		(at 153.1151 97.076095)
		(property "Reference" "TP7"
			(at 1.977805 0.022443 0)
			(unlocked yes)
			(layer "F.SilkS")
			(effects
				(font
					(size 0.635 0.635)
					(thickness 0.1778)
				)
			)
		)
		(property "Value" "1MM"
			(at -2.092783 1.790085 270)
			(unlocked yes)
			(layer "F.SilkS")
			(hide yes)
			(effects
				(font
					(size 0.635 0.635)
					(thickness 0.1778)
				)
			)
		)
		(sheetname "846-XXXXX_SCH_NEO-M9N_MODULE_2_RECEIVER")
		(sheetfile "846-XXXXX_SCH_NEO-M9N_MODULE_2_RECEIVER.kicad_sch")
		(duplicate_pad_numbers_are_jumpers no)
		(pad "1" smd circle
			(at 0 0)
			(size 1 1)
			(layers "F.Cu" "F.Mask" "F.Paste")
			(net "SAFEBOOT_N")
			(solder_paste_margin -100)
			(thermal_bridge_angle 90)
		)
	)
	(footprint "MyLibrary:TP1MM"
		(layer "F.Cu")
		(at 139.7151 113.676095)
		(property "Reference" "TP6"
			(at -0.022443 1.977805 270)
			(unlocked yes)
			(layer "F.SilkS")
			(effects
				(font
					(size 0.635 0.635)
					(thickness 0.1778)
				)
			)
		)
		(property "Value" "1MM"
			(at -2.092793 1.790085 270)
			(unlocked yes)
			(layer "F.SilkS")
			(hide yes)
			(effects
				(font
					(size 0.635 0.635)
					(thickness 0.1778)
				)
			)
		)
		(sheetname "846-XXXXX_SCH_NEO-M9N_MODULE_2_RECEIVER")
		(sheetfile "846-XXXXX_SCH_NEO-M9N_MODULE_2_RECEIVER.kicad_sch")
		(duplicate_pad_numbers_are_jumpers no)
		(pad "1" smd circle
			(at 0 0)
			(size 1 1)
			(layers "F.Cu" "F.Mask" "F.Paste")
			(net "LNA_EN")
			(solder_paste_margin -100)
			(thermal_bridge_angle 90)
		)
	)
	(footprint "MyLibrary:r0402"
		(layer "F.Cu")
		(at 144.2151 96.576095 90)
		(property "Reference" "R1"
			(at 2.077795 0.022393 90)
			(unlocked yes)
			(layer "F.SilkS")
			(effects
				(font
					(size 0.635 0.635)
					(thickness 0.1778)
				)
			)
		)
		(property "Value" "0 ohm 0402"
			(at 2.907145 2.168983 90)
			(unlocked yes)
			(layer "F.SilkS")
			(hide yes)
			(effects
				(font
					(size 0.635 0.635)
					(thickness 0.1778)
				)
			)
		)
		(sheetname "846-XXXXX_SCH_NEO-M9N_MODULE_2_RECEIVER")
		(sheetfile "846-XXXXX_SCH_NEO-M9N_MODULE_2_RECEIVER.kicad_sch")
		(duplicate_pad_numbers_are_jumpers no)
		(fp_line
			(start 0.9906 -0.5334)
			(end 0.9906 0.5334)
			(stroke
				(width 0.1778)
				(type solid)
			)
			(layer "F.SilkS")
		)
		(fp_line
			(start -0.9906 -0.5334)
			(end 0.9906 -0.5334)
			(stroke
				(width 0.1778)
				(type solid)
			)
			(layer "F.SilkS")
		)
		(fp_line
			(start -0.9906 -0.5334)
			(end -0.9906 0.5334)
			(stroke
				(width 0.1778)
				(type solid)
			)
			(layer "F.SilkS")
		)
		(fp_line
			(start -0.9906 0.5334)
			(end 0.9906 0.5334)
			(stroke
				(width 0.1778)
				(type solid)
			)
			(layer "F.SilkS")
		)
		(pad "1" smd rect
			(at -0.5 0 90)
			(size 0.5 0.6)
			(layers "F.Cu" "F.Mask" "F.Paste")
			(net "VDD_USB")
		)
		(pad "2" smd rect
			(at 0.5 0 90)
			(size 0.5 0.6)
			(layers "F.Cu" "F.Mask" "F.Paste")
			(net "GND")
		)
	)
	(footprint "MyLibrary:TP1MM"
		(layer "F.Cu")
		(at 173.42105 99.276095 90)
		(property "Reference" "TP10"
			(at -0.022443 -2.22815 0)
			(unlocked yes)
			(layer "F.SilkS")
			(effects
				(font
					(size 0.635 0.635)
					(thickness 0.1778)
				)
			)
		)
		(property "Value" "1MM"
			(at -2.092783 1.790075 0)
			(unlocked yes)
			(layer "F.SilkS")
			(hide yes)
			(effects
				(font
					(size 0.635 0.635)
					(thickness 0.1778)
				)
			)
		)
		(sheetname "846-XXXXX_SCH_NEO-M9N_MODULE_2_RECEIVER")
		(sheetfile "846-XXXXX_SCH_NEO-M9N_MODULE_2_RECEIVER.kicad_sch")
		(duplicate_pad_numbers_are_jumpers no)
		(pad "1" smd circle
			(at 0 0 90)
			(size 1 1)
			(layers "F.Cu" "F.Mask" "F.Paste")
			(net "RX_GPS")
			(solder_paste_margin -100)
			(thermal_bridge_angle 90)
		)
	)
	(footprint "LotusSound:SOT23"
		(layer "F.Cu")
		(at 127.0151 107.876095 90)
		(property "Reference" "Q1"
			(at -1.222443 -1.722195 0)
			(unlocked yes)
			(layer "F.SilkS")
			(effects
				(font
					(size 0.635 0.635)
					(thickness 0.1778)
				)
			)
		)
		(property "Value" "DMG2302UKQ-7"
			(at 7.883825 3.419602 90)
			(unlocked yes)
			(layer "F.SilkS")
			(hide yes)
			(effects
				(font
					(size 1.524 1.524)
					(thickness 0.254)
				)
			)
		)
		(sheetname "846-XXXXX_SCH_NEO-M9N_MODULE_2_RECEIVER")
		(sheetfile "846-XXXXX_SCH_NEO-M9N_MODULE_2_RECEIVER.kicad_sch")
		(duplicate_pad_numbers_are_jumpers no)
		(fp_line
			(start 0.5334 -1.8542)
			(end 0.5334 -0.9525)
			(stroke
				(width 0.1524)
				(type solid)
			)
			(layer "F.SilkS")
		)
		(fp_line
			(start -0.5334 -1.8542)
			(end 0.5334 -1.8542)
			(stroke
				(width 0.1524)
				(type solid)
			)
			(layer "F.SilkS")
		)
		(fp_line
			(start -0.5334 -1.8542)
			(end -0.5334 -0.9525)
			(stroke
				(width 0.1524)
				(type solid)
			)
			(layer "F.SilkS")
		)
		(fp_line
			(start 1.7526 -0.9525)
			(end 1.7526 0.9525)
			(stroke
				(width 0.1524)
				(type solid)
			)
			(layer "F.SilkS")
		)
		(fp_line
			(start 0.5334 -0.9525)
			(end 1.7526 -0.9525)
			(stroke
				(width 0.1524)
				(type solid)
			)
			(layer "F.SilkS")
		)
		(fp_line
			(start -1.7526 -0.9525)
			(end -0.5334 -0.9525)
			(stroke
				(width 0.1524)
				(type solid)
			)
			(layer "F.SilkS")
		)
		(fp_line
			(start -1.7526 -0.9525)
			(end -1.7526 0.9525)
			(stroke
				(width 0.1524)
				(type solid)
			)
			(layer "F.SilkS")
		)
		(fp_line
			(start 1.4484 0.9525)
			(end 1.7526 0.9525)
			(stroke
				(width 0.1524)
				(type solid)
			)
			(layer "F.SilkS")
		)
		(fp_line
			(start 1.4484 0.9525)
			(end 1.4484 1.8542)
			(stroke
				(width 0.1524)
				(type solid)
			)
			(layer "F.SilkS")
		)
		(fp_line
			(start -1.4484 0.9525)
			(end -1.4484 1.8542)
			(stroke
				(width 0.1524)
				(type solid)
			)
			(layer "F.SilkS")
		)
		(fp_line
			(start -1.7526 0.9525)
			(end -1.4484 0.9525)
			(stroke
				(width 0.1524)
				(type solid)
			)
			(layer "F.SilkS")
		)
		(fp_line
			(start -1.4484 1.8542)
			(end 1.4484 1.8542)
			(stroke
				(width 0.1524)
				(type solid)
			)
			(layer "F.SilkS")
		)
		(fp_circle
			(center -1.778 1.524)
			(end -1.7018 1.524)
			(stroke
				(width 0.1778)
				(type solid)
			)
			(fill no)
			(layer "F.SilkS")
		)
		(pad "1" smd rect
			(at -0.915 0.9652 90)
			(size 0.5588 1.27)
			(layers "F.Cu" "F.Mask" "F.Paste")
			(net "NetQ1_1")
		)
		(pad "2" smd rect
			(at 0.915 0.9652 90)
			(size 0.5588 1.27)
			(layers "F.Cu" "F.Mask" "F.Paste")
			(net "+5V")
		)
		(pad "3" smd rect
			(at 0 -0.9652 90)
			(size 0.5588 1.27)
			(layers "F.Cu" "F.Mask" "F.Paste")
			(net "NetQ1_3")
		)
	)
	(footprint "MyLibrary:TP1MM"
		(layer "F.Cu")
		(at 147.11497 97.161445)
		(property "Reference" "TP3"
			(at 0.022563 -1.663155 90)
			(unlocked yes)
			(layer "F.SilkS")
			(effects
				(font
					(size 0.635 0.635)
					(thickness 0.1778)
				)
			)
		)
		(property "Value" "1MM"
			(at -2.092783 1.790085 270)
			(unlocked yes)
			(layer "F.SilkS")
			(hide yes)
			(effects
				(font
					(size 0.635 0.635)
					(thickness 0.1778)
				)
			)
		)
		(sheetname "846-XXXXX_SCH_NEO-M9N_MODULE_2_RECEIVER")
		(sheetfile "846-XXXXX_SCH_NEO-M9N_MODULE_2_RECEIVER.kicad_sch")
		(duplicate_pad_numbers_are_jumpers no)
		(pad "1" smd circle
			(at 0 0)
			(size 1 1)
			(layers "F.Cu" "F.Mask" "F.Paste")
			(net "USB_DP")
			(solder_paste_margin -100)
			(thermal_bridge_angle 90)
		)
	)
	(footprint "MyLibrary:TP1MM"
		(layer "F.Cu")
		(at 145.4151 113.676095)
		(property "Reference" "TP8"
			(at -0.022443 1.977805 270)
			(unlocked yes)
			(layer "F.SilkS")
			(effects
				(font
					(size 0.635 0.635)
					(thickness 0.1778)
				)
			)
		)
		(property "Value" "1MM"
			(at -2.092783 1.790085 270)
			(unlocked yes)
			(layer "F.SilkS")
			(hide yes)
			(effects
				(font
					(size 0.635 0.635)
					(thickness 0.1778)
				)
			)
		)
		(sheetname "846-XXXXX_SCH_NEO-M9N_MODULE_2_RECEIVER")
		(sheetfile "846-XXXXX_SCH_NEO-M9N_MODULE_2_RECEIVER.kicad_sch")
		(duplicate_pad_numbers_are_jumpers no)
		(pad "1" smd circle
			(at 0 0)
			(size 1 1)
			(layers "F.Cu" "F.Mask" "F.Paste")
			(net "SDA_SPI_CS_N")
			(solder_paste_margin -100)
			(thermal_bridge_angle 90)
		)
	)
	(footprint "MyLibrary:TP1MM"
		(layer "F.Cu")
		(at 175.97619 99.276095 90)
		(property "Reference" "TP11"
			(at -0.022443 2.11671 0)
			(unlocked yes)
			(layer "F.SilkS")
			(effects
				(font
					(size 0.635 0.635)
					(thickness 0.1778)
				)
			)
		)
		(property "Value" "1MM"
			(at -2.092783 1.790085 0)
			(unlocked yes)
			(layer "F.SilkS")
			(hide yes)
			(effects
				(font
					(size 0.635 0.635)
					(thickness 0.1778)
				)
			)
		)
		(sheetname "846-XXXXX_SCH_NEO-M9N_MODULE_2_RECEIVER")
		(sheetfile "846-XXXXX_SCH_NEO-M9N_MODULE_2_RECEIVER.kicad_sch")
		(duplicate_pad_numbers_are_jumpers no)
		(pad "1" smd circle
			(at 0 0 90)
			(size 1 1)
			(layers "F.Cu" "F.Mask" "F.Paste")
			(net "TX_GPS")
			(solder_paste_margin -100)
			(thermal_bridge_angle 90)
		)
	)
	(footprint "MyLibrary:r0402"
		(layer "F.Cu")
		(at 167.7151 109.976095 90)
		(property "Reference" "R3"
			(at 2.277805 0.122433 90)
			(unlocked yes)
			(layer "F.SilkS")
			(effects
				(font
					(size 0.635 0.635)
					(thickness 0.1778)
				)
			)
		)
		(property "Value" "10K 1/8W 0402"
			(at 4.938495 2.168983 90)
			(unlocked yes)
			(layer "F.SilkS")
			(hide yes)
			(effects
				(font
					(size 0.635 0.635)
					(thickness 0.1778)
				)
			)
		)
		(sheetname "846-XXXXX_SCH_NEO-M9N_MODULE_2_RECEIVER")
		(sheetfile "846-XXXXX_SCH_NEO-M9N_MODULE_2_RECEIVER.kicad_sch")
		(duplicate_pad_numbers_are_jumpers no)
		(fp_line
			(start 0.9906 -0.5334)
			(end 0.9906 0.5334)
			(stroke
				(width 0.1778)
				(type solid)
			)
			(layer "F.SilkS")
		)
		(fp_line
			(start -0.9906 -0.5334)
			(end 0.9906 -0.5334)
			(stroke
				(width 0.1778)
				(type solid)
			)
			(layer "F.SilkS")
		)
		(fp_line
			(start -0.9906 -0.5334)
			(end -0.9906 0.5334)
			(stroke
				(width 0.1778)
				(type solid)
			)
			(layer "F.SilkS")
		)
		(fp_line
			(start -0.9906 0.5334)
			(end 0.9906 0.5334)
			(stroke
				(width 0.1778)
				(type solid)
			)
			(layer "F.SilkS")
		)
		(pad "1" smd rect
			(at -0.5 0 90)
			(size 0.5 0.6)
			(layers "F.Cu" "F.Mask" "F.Paste")
			(net "GND")
		)
		(pad "2" smd rect
			(at 0.5 0 90)
			(size 0.5 0.6)
			(layers "F.Cu" "F.Mask" "F.Paste")
			(net "NetLED2_2")
		)
	)
	(footprint "MyLibrary:L0402"
		(layer "F.Cu")
		(at 125.70276 101.476095 90)
		(property "Reference" "L1"
			(at -0.422433 1.490145 0)
			(unlocked yes)
			(layer "F.SilkS")
			(effects
				(font
					(size 0.635 0.635)
					(thickness 0.1778)
				)
			)
		)
		(property "Value" "27nH 300mA 460mohm 0402"
			(at 12.962345 2.118183 90)
			(unlocked yes)
			(layer "F.SilkS")
			(hide yes)
			(effects
				(font
					(size 0.635 0.635)
					(thickness 0.1778)
				)
			)
		)
		(sheetname "846-XXXXX_SCH_NEO-M9N_MODULE_2_RECEIVER")
		(sheetfile "846-XXXXX_SCH_NEO-M9N_MODULE_2_RECEIVER.kicad_sch")
		(duplicate_pad_numbers_are_jumpers no)
		(fp_line
			(start 0.84279 -0.47866)
			(end 0.84279 0.48654)
			(stroke
				(width 0.1778)
				(type solid)
			)
			(layer "F.SilkS")
		)
		(fp_line
			(start -0.83361 -0.47866)
			(end 0.84279 -0.47866)
			(stroke
				(width 0.1778)
				(type solid)
			)
			(layer "F.SilkS")
		)
		(fp_line
			(start -0.83361 -0.47866)
			(end -0.83361 0.48654)
			(stroke
				(width 0.1778)
				(type solid)
			)
			(layer "F.SilkS")
		)
		(fp_line
			(start -0.83361 0.48654)
			(end 0.84279 0.48654)
			(stroke
				(width 0.1778)
				(type solid)
			)
			(layer "F.SilkS")
		)
		(pad "1" smd rect
			(at -0.4 0 90)
			(size 0.4 0.5)
			(layers "F.Cu" "F.Mask" "F.Paste")
			(net "NetC5_2")
		)
		(pad "2" smd rect
			(at 0.4 0 90)
			(size 0.4 0.5)
			(layers "F.Cu" "F.Mask" "F.Paste")
			(net "RF_ANT")
		)
	)
	(footprint "MyLibrary:c0402"
		(layer "F.Cu")
		(at 151.67081 114.176095 90)
		(property "Reference" "C2"
			(at -3.083605 -0.072443 270)
			(unlocked yes)
			(layer "F.SilkS")
			(effects
				(font
					(size 0.635 0.635)
					(thickness 0.1778)
				)
			)
		)
		(property "Value" "100nF 10V 0402"
			(at 5.700245 2.118183 90)
			(unlocked yes)
			(layer "F.SilkS")
			(hide yes)
			(effects
				(font
					(size 0.635 0.635)
					(thickness 0.1778)
				)
			)
		)
		(sheetname "846-XXXXX_SCH_NEO-M9N_MODULE_2_RECEIVER")
		(sheetfile "846-XXXXX_SCH_NEO-M9N_MODULE_2_RECEIVER.kicad_sch")
		(duplicate_pad_numbers_are_jumpers no)
		(fp_line
			(start 0.9906 -0.4826)
			(end 0.9906 0.4826)
			(stroke
				(width 0.1778)
				(type solid)
			)
			(layer "F.SilkS")
		)
		(fp_line
			(start -0.9906 -0.4826)
			(end 0.9906 -0.4826)
			(stroke
				(width 0.1778)
				(type solid)
			)
			(layer "F.SilkS")
		)
		(fp_line
			(start -0.9906 -0.4826)
			(end -0.9906 0.4826)
			(stroke
				(width 0.1778)
				(type solid)
			)
			(layer "F.SilkS")
		)
		(fp_line
			(start -0.9906 0.4826)
			(end 0.9906 0.4826)
			(stroke
				(width 0.1778)
				(type solid)
			)
			(layer "F.SilkS")
		)
		(pad "1" smd rect
			(at -0.5 0 90)
			(size 0.5 0.5)
			(layers "F.Cu" "F.Mask" "F.Paste")
			(net "GND")
		)
		(pad "2" smd rect
			(at 0.5 0 90)
			(size 0.5 0.5)
			(layers "F.Cu" "F.Mask" "F.Paste")
			(net "+3V3")
		)
	)
	(footprint "MyLibrary:r0402"
		(layer "F.Cu")
		(at 153.6151 95.476095 180)
		(property "Reference" "R10"
			(at -2.177805 -0.122443 0)
			(unlocked yes)
			(layer "F.SilkS")
			(effects
				(font
					(size 0.635 0.635)
					(thickness 0.1778)
				)
			)
		)
		(property "Value" "0 ohm 0402"
			(at 2.907155 2.168983 180)
			(unlocked yes)
			(layer "F.SilkS")
			(hide yes)
			(effects
				(font
					(size 0.635 0.635)
					(thickness 0.1778)
				)
			)
		)
		(sheetname "846-XXXXX_SCH_NEO-M9N_MODULE_2_RECEIVER")
		(sheetfile "846-XXXXX_SCH_NEO-M9N_MODULE_2_RECEIVER.kicad_sch")
		(duplicate_pad_numbers_are_jumpers no)
		(fp_line
			(start 0.9906 0.5334)
			(end -0.9906 0.5334)
			(stroke
				(width 0.1778)
				(type solid)
			)
			(layer "F.SilkS")
		)
		(fp_line
			(start 0.9906 -0.5334)
			(end 0.9906 0.5334)
			(stroke
				(width 0.1778)
				(type solid)
			)
			(layer "F.SilkS")
		)
		(fp_line
			(start 0.9906 -0.5334)
			(end -0.9906 -0.5334)
			(stroke
				(width 0.1778)
				(type solid)
			)
			(layer "F.SilkS")
		)
		(fp_line
			(start -0.9906 -0.5334)
			(end -0.9906 0.5334)
			(stroke
				(width 0.1778)
				(type solid)
			)
			(layer "F.SilkS")
		)
		(pad "1" smd rect
			(at -0.5 0 180)
			(size 0.5 0.6)
			(layers "F.Cu" "F.Mask" "F.Paste")
			(net "GND")
		)
		(pad "2" smd rect
			(at 0.5 0 180)
			(size 0.5 0.6)
			(layers "F.Cu" "F.Mask" "F.Paste")
			(net "D_SEL")
		)
	)
	(footprint "MyLibrary:TP1MM"
		(layer "F.Cu")
		(at 151.5151 97.076095)
		(property "Reference" "TP1"
			(at 0.022443 -1.877805 90)
			(unlocked yes)
			(layer "F.SilkS")
			(effects
				(font
					(size 0.635 0.635)
					(thickness 0.1778)
				)
			)
		)
		(property "Value" "1MM"
			(at -2.092783 1.790085 270)
			(unlocked yes)
			(layer "F.SilkS")
			(hide yes)
			(effects
				(font
					(size 0.635 0.635)
					(thickness 0.1778)
				)
			)
		)
		(sheetname "846-XXXXX_SCH_NEO-M9N_MODULE_2_RECEIVER")
		(sheetfile "846-XXXXX_SCH_NEO-M9N_MODULE_2_RECEIVER.kicad_sch")
		(duplicate_pad_numbers_are_jumpers no)
		(pad "1" smd circle
			(at 0 0)
			(size 1 1)
			(layers "F.Cu" "F.Mask" "F.Paste")
			(net "D_SEL")
			(solder_paste_margin -100)
			(thermal_bridge_angle 90)
		)
	)
	(footprint "MyLibrary:IC_NEO-M9N"
		(layer "F.Cu")
		(at 145.6151 105.376095 90)
		(property "Reference" "U1"
			(at -6.722433 -8.722205 0)
			(unlocked yes)
			(layer "F.SilkS")
			(effects
				(font
					(size 0.635 0.635)
					(thickness 0.1778)
				)
			)
		)
		(property "Value" "NEO-M9N-00B"
			(at -1.74154 9.661983 90)
			(unlocked yes)
			(layer "F.SilkS")
			(hide yes)
			(effects
				(font
					(size 0.635 0.635)
					(thickness 0.1778)
				)
			)
		)
		(sheetname "846-XXXXX_SCH_NEO-M9N_MODULE_2_RECEIVER")
		(sheetfile "846-XXXXX_SCH_NEO-M9N_MODULE_2_RECEIVER.kicad_sch")
		(duplicate_pad_numbers_are_jumpers no)
		(fp_line
			(start 7.1755 -8.025)
			(end 7.1755 8.025)
			(stroke
				(width 0.1778)
				(type solid)
			)
			(layer "F.SilkS")
		)
		(fp_line
			(start -7.1755 -8.025)
			(end 7.1755 -8.025)
			(stroke
				(width 0.1778)
				(type solid)
			)
			(layer "F.SilkS")
		)
		(fp_line
			(start -7.1755 -8.025)
			(end -7.1755 8.025)
			(stroke
				(width 0.1778)
				(type solid)
			)
			(layer "F.SilkS")
		)
		(fp_line
			(start -7.1755 8.025)
			(end 7.1755 8.025)
			(stroke
				(width 0.1778)
				(type solid)
			)
			(layer "F.SilkS")
		)
		(fp_rect
			(start 3.699995 8.024995)
			(end 7.175485 7.574995)
			(stroke
				(width 0)
				(type default)
			)
			(fill yes)
			(layer "F.SilkS")
		)
		(fp_rect
			(start -5.80173 -7.40106)
			(end -7.00823 -6.60096)
			(stroke
				(width 0)
				(type default)
			)
			(fill yes)
			(layer "F.Paste")
		)
		(fp_rect
			(start -4.915905 -7.299465)
			(end -5.811255 -6.702565)
			(stroke
				(width 0)
				(type default)
			)
			(fill yes)
			(layer "F.Paste")
		)
		(fp_rect
			(start 4.915535 -6.702575)
			(end 5.810885 -7.299475)
			(stroke
				(width 0)
				(type default)
			)
			(fill yes)
			(layer "F.Paste")
		)
		(fp_rect
			(start 5.80136 -6.60098)
			(end 7.00786 -7.40108)
			(stroke
				(width 0)
				(type default)
			)
			(fill yes)
			(layer "F.Paste")
		)
		(fp_rect
			(start -5.80174 -6.30108)
			(end -7.00824 -5.50098)
			(stroke
				(width 0)
				(type default)
			)
			(fill yes)
			(layer "F.Paste")
		)
		(fp_rect
			(start -4.915915 -6.199485)
			(end -5.811265 -5.602585)
			(stroke
				(width 0)
				(type default)
			)
			(fill yes)
			(layer "F.Paste")
		)
		(fp_rect
			(start 4.915535 -5.602585)
			(end 5.810885 -6.199485)
			(stroke
				(width 0)
				(type default)
			)
			(fill yes)
			(layer "F.Paste")
		)
		(fp_rect
			(start 5.80136 -5.50098)
			(end 7.00786 -6.30108)
			(stroke
				(width 0)
				(type default)
			)
			(fill yes)
			(layer "F.Paste")
		)
		(fp_rect
			(start -5.80173 -5.20106)
			(end -7.00823 -4.40096)
			(stroke
				(width 0)
				(type default)
			)
			(fill yes)
			(layer "F.Paste")
		)
		(fp_rect
			(start -4.915905 -5.099465)
			(end -5.811255 -4.502565)
			(stroke
				(width 0)
				(type default)
			)
			(fill yes)
			(layer "F.Paste")
		)
		(fp_rect
			(start 4.915535 -4.502575)
			(end 5.810885 -5.099475)
			(stroke
				(width 0)
				(type default)
			)
			(fill yes)
			(layer "F.Paste")
		)
		(fp_rect
			(start 5.80136 -4.40098)
			(end 7.00786 -5.20108)
			(stroke
				(width 0)
				(type default)
			)
			(fill yes)
			(layer "F.Paste")
		)
		(fp_rect
			(start -5.80174 -4.10108)
			(end -7.00824 -3.30098)
			(stroke
				(width 0)
				(type default)
			)
			(fill yes)
			(layer "F.Paste")
		)
		(fp_rect
			(start -4.915915 -3.999475)
			(end -5.811265 -3.402575)
			(stroke
				(width 0)
				(type default)
			)
			(fill yes)
			(layer "F.Paste")
		)
		(fp_rect
			(start 4.915535 -3.402575)
			(end 5.810885 -3.999475)
			(stroke
				(width 0)
				(type default)
			)
			(fill yes)
			(layer "F.Paste")
		)
		(fp_rect
			(start 5.80136 -3.30098)
			(end 7.00786 -4.10108)
			(stroke
				(width 0)
				(type default)
			)
			(fill yes)
			(layer "F.Paste")
		)
		(fp_rect
			(start -5.80174 -3.00108)
			(end -7.00824 -2.20098)
			(stroke
				(width 0)
				(type default)
			)
			(fill yes)
			(layer "F.Paste")
		)
		(fp_rect
			(start -4.915915 -2.899485)
			(end -5.811265 -2.302585)
			(stroke
				(width 0)
				(type default)
			)
			(fill yes)
			(layer "F.Paste")
		)
		(fp_rect
			(start 4.915535 -2.302585)
			(end 5.810885 -2.899485)
			(stroke
				(width 0)
				(type default)
			)
			(fill yes)
			(layer "F.Paste")
		)
		(fp_rect
			(start 5.80136 -2.20098)
			(end 7.00786 -3.00108)
			(stroke
				(width 0)
				(type default)
			)
			(fill yes)
			(layer "F.Paste")
		)
		(fp_rect
			(start -5.80174 -0.00108)
			(end -7.00824 0.79902)
			(stroke
				(width 0)
				(type default)
			)
			(fill yes)
			(layer "F.Paste")
		)
		(fp_rect
			(start -4.915925 0.100515)
			(end -5.811275 0.697415)
			(stroke
				(width 0)
				(type default)
			)
			(fill yes)
			(layer "F.Paste")
		)
		(fp_rect
			(start 4.915515 0.697405)
			(end 5.810865 0.100505)
			(stroke
				(width 0)
				(type default)
			)
			(fill yes)
			(layer "F.Paste")
		)
		(fp_rect
			(start 5.80136 0.79902)
			(end 7.00786 -0.00108)
			(stroke
				(width 0)
				(type default)
			)
			(fill yes)
			(layer "F.Paste")
		)
		(fp_rect
			(start -5.80174 1.09892)
			(end -7.00824 1.89902)
			(stroke
				(width 0)
				(type default)
			)
			(fill yes)
			(layer "F.Paste")
		)
		(fp_rect
			(start -4.915915 1.200515)
			(end -5.811265 1.797415)
			(stroke
				(width 0)
				(type default)
			)
			(fill yes)
			(layer "F.Paste")
		)
		(fp_rect
			(start 4.915535 1.797415)
			(end 5.810885 1.200515)
			(stroke
				(width 0)
				(type default)
			)
			(fill yes)
			(layer "F.Paste")
		)
		(fp_rect
			(start 5.80136 1.89902)
			(end 7.00786 1.09892)
			(stroke
				(width 0)
				(type default)
			)
			(fill yes)
			(layer "F.Paste")
		)
		(fp_rect
			(start -5.80175 2.19892)
			(end -7.00825 2.99902)
			(stroke
				(width 0)
				(type default)
			)
			(fill yes)
			(layer "F.Paste")
		)
		(fp_rect
			(start -4.915925 2.300515)
			(end -5.811275 2.897415)
			(stroke
				(width 0)
				(type default)
			)
			(fill yes)
			(layer "F.Paste")
		)
		(fp_rect
			(start 4.915515 2.897405)
			(end 5.810865 2.300505)
			(stroke
				(width 0)
				(type default)
			)
			(fill yes)
			(layer "F.Paste")
		)
		(fp_rect
			(start 5.80134 2.999)
			(end 7.00784 2.1989)
			(stroke
				(width 0)
				(type default)
			)
			(fill yes)
			(layer "F.Paste")
		)
		(fp_rect
			(start -5.80175 3.29892)
			(end -7.00825 4.09902)
			(stroke
				(width 0)
				(type default)
			)
			(fill yes)
			(layer "F.Paste")
		)
		(fp_rect
			(start -4.915925 3.400515)
			(end -5.811275 3.997415)
			(stroke
				(width 0)
				(type default)
			)
			(fill yes)
			(layer "F.Paste")
		)
		(fp_rect
			(start 4.915515 3.997405)
			(end 5.810865 3.400505)
			(stroke
				(width 0)
				(type default)
			)
			(fill yes)
			(layer "F.Paste")
		)
		(fp_rect
			(start 5.80134 4.099)
			(end 7.00784 3.2989)
			(stroke
				(width 0)
				(type default)
			)
			(fill yes)
			(layer "F.Paste")
		)
		(fp_rect
			(start -5.80174 4.39892)
			(end -7.00824 5.19902)
			(stroke
				(width 0)
				(type default)
			)
			(fill yes)
			(layer "F.Paste")
		)
		(fp_rect
			(start -4.915915 4.500515)
			(end -5.811265 5.097415)
			(stroke
				(width 0)
				(type default)
			)
			(fill yes)
			(layer "F.Paste")
		)
		(fp_rect
			(start 4.915535 5.097415)
			(end 5.810885 4.500515)
			(stroke
				(width 0)
				(type default)
			)
			(fill yes)
			(layer "F.Paste")
		)
		(fp_rect
			(start 5.80136 5.19902)
			(end 7.00786 4.39892)
			(stroke
				(width 0)
				(type default)
			)
			(fill yes)
			(layer "F.Paste")
		)
		(fp_rect
			(start -5.80175 5.49892)
			(end -7.00825 6.29902)
			(stroke
				(width 0)
				(type default)
			)
			(fill yes)
			(layer "F.Paste")
		)
		(fp_rect
			(start -4.915925 5.600515)
			(end -5.811275 6.197415)
			(stroke
				(width 0)
				(type default)
			)
			(fill yes)
			(layer "F.Paste")
		)
		(fp_rect
			(start 4.915515 6.197405)
			(end 5.810865 5.600505)
			(stroke
				(width 0)
				(type default)
			)
			(fill yes)
			(layer "F.Paste")
		)
		(fp_rect
			(start 5.80134 6.299)
			(end 7.00784 5.4989)
			(stroke
				(width 0)
				(type default)
			)
			(fill yes)
			(layer "F.Paste")
		)
		(fp_rect
			(start -5.80174 6.59892)
			(end -7.00824 7.39902)
			(stroke
				(width 0)
				(type default)
			)
			(fill yes)
			(layer "F.Paste")
		)
		(fp_rect
			(start -4.915915 6.700515)
			(end -5.811265 7.297415)
			(stroke
				(width 0)
				(type default)
			)
			(fill yes)
			(layer "F.Paste")
		)
		(fp_rect
			(start 4.915535 7.297415)
			(end 5.810885 6.700515)
			(stroke
				(width 0)
				(type default)
			)
			(fill yes)
			(layer "F.Paste")
		)
		(fp_rect
			(start 5.80136 7.39902)
			(end 7.00786 6.59892)
			(stroke
				(width 0)
				(type default)
			)
			(fill yes)
			(layer "F.Paste")
		)
		(pad "1" smd rect
			(at 6.09981 6.99897 90)
			(size 1.79832 0.8001)
			(layers "F.Cu" "F.Mask" "F.Paste")
			(net "SAFEBOOT_N")
			(solder_paste_margin -2147.48364)
		)
		(pad "2" smd rect
			(at 6.09981 5.89915 90)
			(size 1.79832 0.8001)
			(layers "F.Cu" "F.Mask" "F.Paste")
			(net "D_SEL")
			(solder_paste_margin -2147.48364)
		)
		(pad "3" smd rect
			(at 6.09981 4.79933 90)
			(size 1.79832 0.8001)
			(layers "F.Cu" "F.Mask" "F.Paste")
			(net "TP1")
			(solder_paste_margin -2147.48364)
		)
		(pad "4" smd rect
			(at 6.09981 3.69951 90)
			(size 1.79832 0.8001)
			(layers "F.Cu" "F.Mask" "F.Paste")
			(net "EXTIN")
			(solder_paste_margin -2147.48364)
		)
		(pad "5" smd rect
			(at 6.09981 2.59969 90)
			(size 1.79832 0.8001)
			(layers "F.Cu" "F.Mask" "F.Paste")
			(net "USB_DM")
			(solder_paste_margin -2147.48364)
		)
		(pad "6" smd rect
			(at 6.09981 1.49987 90)
			(size 1.79832 0.8001)
			(layers "F.Cu" "F.Mask" "F.Paste")
			(net "USB_DP")
			(solder_paste_margin -2147.48364)
		)
		(pad "7" smd rect
			(at 6.09981 0.40005 90)
			(size 1.79832 0.8001)
			(layers "F.Cu" "F.Mask" "F.Paste")
			(net "VDD_USB")
			(solder_paste_margin -2147.48364)
		)
		(pad "8" smd rect
			(at 6.09981 -2.59969 90)
			(size 1.79832 0.8001)
			(layers "F.Cu" "F.Mask" "F.Paste")
			(net "RST_GPS")
			(solder_paste_margin -2147.48364)
		)
		(pad "9" smd rect
			(at 6.09981 -3.69951 90)
			(size 1.79832 0.8001)
			(layers "F.Cu" "F.Mask" "F.Paste")
			(solder_paste_margin -2147.48364)
		)
		(pad "10" smd rect
			(at 6.09981 -4.79933 90)
			(size 1.79832 0.8001)
			(layers "F.Cu" "F.Mask" "F.Paste")
			(net "GND")
			(solder_paste_margin -2147.48364)
		)
		(pad "11" smd rect
			(at 6.09981 -5.89915 90)
			(size 1.79832 0.8001)
			(layers "F.Cu" "F.Mask" "F.Paste")
			(net "RF_MODULE")
			(solder_paste_margin -2147.48364)
		)
		(pad "12" smd rect
			(at 6.09981 -6.99897 90)
			(size 1.79832 0.8001)
			(layers "F.Cu" "F.Mask" "F.Paste")
			(net "GND")
			(solder_paste_margin -2147.48364)
		)
		(pad "13" smd rect
			(at -6.09981 -6.99897 90)
			(size 1.79832 0.8001)
			(layers "F.Cu" "F.Mask" "F.Paste")
			(net "GND")
			(solder_paste_margin -2147.48364)
		)
		(pad "14" smd rect
			(at -6.09981 -5.89915 90)
			(size 1.79832 0.8001)
			(layers "F.Cu" "F.Mask" "F.Paste")
			(net "LNA_EN")
			(solder_paste_margin -2147.48364)
		)
		(pad "15" smd rect
			(at -6.09981 -4.79933 90)
			(size 1.79832 0.8001)
			(layers "F.Cu" "F.Mask" "F.Paste")
			(solder_paste_margin -2147.48364)
		)
		(pad "16" smd rect
			(at -6.09981 -3.69951 90)
			(size 1.79832 0.8001)
			(layers "F.Cu" "F.Mask" "F.Paste")
			(solder_paste_margin -2147.48364)
		)
		(pad "17" smd rect
			(at -6.09981 -2.59969 90)
			(size 1.79832 0.8001)
			(layers "F.Cu" "F.Mask" "F.Paste")
			(solder_paste_margin -2147.48364)
		)
		(pad "18" smd rect
			(at -6.09981 0.40005 90)
			(size 1.79832 0.8001)
			(layers "F.Cu" "F.Mask" "F.Paste")
			(net "SDA_SPI_CS_N")
			(solder_paste_margin -2147.48364)
		)
		(pad "19" smd rect
			(at -6.09981 1.49987 90)
			(size 1.79832 0.8001)
			(layers "F.Cu" "F.Mask" "F.Paste")
			(net "SCL_SPI_CLK")
			(solder_paste_margin -2147.48364)
		)
		(pad "20" smd rect
			(at -6.09981 2.59969 90)
			(size 1.79832 0.8001)
			(layers "F.Cu" "F.Mask" "F.Paste")
			(net "TX_GPS")
			(solder_paste_margin -2147.48364)
		)
		(pad "21" smd rect
			(at -6.09981 3.69951 90)
			(size 1.79832 0.8001)
			(layers "F.Cu" "F.Mask" "F.Paste")
			(net "RX_GPS")
			(solder_paste_margin -2147.48364)
		)
		(pad "22" smd rect
			(at -6.09981 4.79933 90)
			(size 1.79832 0.8001)
			(layers "F.Cu" "F.Mask" "F.Paste")
			(net "+3V3")
			(solder_paste_margin -2147.48364)
		)
		(pad "23" smd rect
			(at -6.09981 5.89915 90)
			(size 1.79832 0.8001)
			(layers "F.Cu" "F.Mask" "F.Paste")
			(net "+3V3")
			(solder_paste_margin -2147.48364)
		)
		(pad "24" smd rect
			(at -6.09981 6.99897 90)
			(size 1.79832 0.8001)
			(layers "F.Cu" "F.Mask" "F.Paste")
			(net "GND")
			(solder_paste_margin -2147.48364)
		)
	)
	(footprint "MyLibrary:c0402"
		(layer "F.Cu")
		(at 150.1151 114.176095 90)
		(property "Reference" "C1"
			(at -2.977795 -0.022443 270)
			(unlocked yes)
			(layer "F.SilkS")
			(effects
				(font
					(size 0.635 0.635)
					(thickness 0.1778)
				)
			)
		)
		(property "Value" "1uF 6V3 0402"
			(at 4.3037 2.118183 90)
			(unlocked yes)
			(layer "F.SilkS")
			(hide yes)
			(effects
				(font
					(size 0.635 0.635)
					(thickness 0.1778)
				)
			)
		)
		(sheetname "846-XXXXX_SCH_NEO-M9N_MODULE_2_RECEIVER")
		(sheetfile "846-XXXXX_SCH_NEO-M9N_MODULE_2_RECEIVER.kicad_sch")
		(duplicate_pad_numbers_are_jumpers no)
		(fp_line
			(start 0.9906 -0.4826)
			(end 0.9906 0.4826)
			(stroke
				(width 0.1778)
				(type solid)
			)
			(layer "F.SilkS")
		)
		(fp_line
			(start -0.9906 -0.4826)
			(end 0.9906 -0.4826)
			(stroke
				(width 0.1778)
				(type solid)
			)
			(layer "F.SilkS")
		)
		(fp_line
			(start -0.9906 -0.4826)
			(end -0.9906 0.4826)
			(stroke
				(width 0.1778)
				(type solid)
			)
			(layer "F.SilkS")
		)
		(fp_line
			(start -0.9906 0.4826)
			(end 0.9906 0.4826)
			(stroke
				(width 0.1778)
				(type solid)
			)
			(layer "F.SilkS")
		)
		(pad "1" smd rect
			(at -0.5 0 90)
			(size 0.5 0.5)
			(layers "F.Cu" "F.Mask" "F.Paste")
			(net "GND")
		)
		(pad "2" smd rect
			(at 0.5 0 90)
			(size 0.5 0.5)
			(layers "F.Cu" "F.Mask" "F.Paste")
			(net "+3V3")
		)
	)
	(footprint "MyLibrary:r0402"
		(layer "F.Cu")
		(at 173.42105 101.376095 -90)
		(property "Reference" "R5"
			(at 1.622443 -0.171845 0)
			(unlocked yes)
			(layer "F.SilkS")
			(effects
				(font
					(size 0.635 0.635)
					(thickness 0.1778)
				)
			)
		)
		(property "Value" "0 ohm 0402"
			(at 2.907155 2.168993 270)
			(unlocked yes)
			(layer "F.SilkS")
			(hide yes)
			(effects
				(font
					(size 0.635 0.635)
					(thickness 0.1778)
				)
			)
		)
		(sheetname "846-XXXXX_SCH_NEO-M9N_MODULE_2_RECEIVER")
		(sheetfile "846-XXXXX_SCH_NEO-M9N_MODULE_2_RECEIVER.kicad_sch")
		(duplicate_pad_numbers_are_jumpers no)
		(fp_line
			(start -0.9906 0.5334)
			(end -0.9906 -0.5334)
			(stroke
				(width 0.1778)
				(type solid)
			)
			(layer "F.SilkS")
		)
		(fp_line
			(start 0.9906 0.5334)
			(end -0.9906 0.5334)
			(stroke
				(width 0.1778)
				(type solid)
			)
			(layer "F.SilkS")
		)
		(fp_line
			(start 0.9906 0.5334)
			(end 0.9906 -0.5334)
			(stroke
				(width 0.1778)
				(type solid)
			)
			(layer "F.SilkS")
		)
		(fp_line
			(start 0.9906 -0.5334)
			(end -0.9906 -0.5334)
			(stroke
				(width 0.1778)
				(type solid)
			)
			(layer "F.SilkS")
		)
		(pad "1" smd rect
			(at -0.5 0 270)
			(size 0.5 0.6)
			(layers "F.Cu" "F.Mask" "F.Paste")
			(net "RX_GPS")
		)
		(pad "2" smd rect
			(at 0.5 0 270)
			(size 0.5 0.6)
			(layers "F.Cu" "F.Mask" "F.Paste")
			(net "RX_GPS_CONN")
		)
	)
	(gr_arc
		(start 114.9131 90.200096)
		(mid 115.226434 89.443139)
		(end 115.983097 89.129095)
		(stroke
			(width 0.05)
			(type solid)
		)
		(layer "Edge.Cuts")
	)
	(gr_line
		(start 114.9151 119.831095)
		(end 114.9131 90.200096)
		(stroke
			(width 0.05)
			(type solid)
		)
		(layer "Edge.Cuts")
	)
	(gr_line
		(start 114.9151 119.831094)
		(end 114.9151 119.831095)
		(stroke
			(width 0.05)
			(type solid)
		)
		(layer "Edge.Cuts")
	)
	(gr_arc
		(start 115.9601 120.876095)
		(mid 115.221173 120.570021)
		(end 114.9151 119.831094)
		(stroke
			(width 0.05)
			(type solid)
		)
		(layer "Edge.Cuts")
	)
	(gr_line
		(start 115.983097 89.129095)
		(end 115.9831 89.129095)
		(stroke
			(width 0.05)
			(type solid)
		)
		(layer "Edge.Cuts")
	)
	(gr_line
		(start 115.9831 89.129095)
		(end 181.0091 89.127095)
		(stroke
			(width 0.05)
			(type solid)
		)
		(layer "Edge.Cuts")
	)
	(gr_arc
		(start 116.2161 91.980095)
		(mid 116.670084 90.884079)
		(end 117.7661 90.430095)
		(stroke
			(width 0.05)
			(type solid)
		)
		(layer "Edge.Cuts")
	)
	(gr_arc
		(start 116.2161 117.980095)
		(mid 116.670084 116.884079)
		(end 117.7661 116.430095)
		(stroke
			(width 0.05)
			(type solid)
		)
		(layer "Edge.Cuts")
	)
	(gr_arc
		(start 117.7661 90.430095)
		(mid 118.862116 90.884079)
		(end 119.3161 91.980095)
		(stroke
			(width 0.05)
			(type solid)
		)
		(layer "Edge.Cuts")
	)
	(gr_arc
		(start 117.7661 93.530095)
		(mid 116.670084 93.076111)
		(end 116.2161 91.980095)
		(stroke
			(width 0.05)
			(type solid)
		)
		(layer "Edge.Cuts")
	)
	(gr_arc
		(start 117.7661 116.430095)
		(mid 118.862116 116.884079)
		(end 119.3161 117.980095)
		(stroke
			(width 0.05)
			(type solid)
		)
		(layer "Edge.Cuts")
	)
	(gr_arc
		(start 117.7661 119.530095)
		(mid 116.670084 119.076111)
		(end 116.2161 117.980095)
		(stroke
			(width 0.05)
			(type solid)
		)
		(layer "Edge.Cuts")
	)
	(gr_arc
		(start 119.3161 91.980095)
		(mid 118.862116 93.076111)
		(end 117.7661 93.530095)
		(stroke
			(width 0.05)
			(type solid)
		)
		(layer "Edge.Cuts")
	)
	(gr_arc
		(start 119.3161 117.980095)
		(mid 118.862116 119.076111)
		(end 117.7661 119.530095)
		(stroke
			(width 0.05)
			(type solid)
		)
		(layer "Edge.Cuts")
	)
	(gr_arc
		(start 176.7161 91.980095)
		(mid 177.170084 90.884079)
		(end 178.2661 90.430095)
		(stroke
			(width 0.05)
			(type solid)
		)
		(layer "Edge.Cuts")
	)
	(gr_arc
		(start 176.7161 117.980095)
		(mid 177.170084 116.884079)
		(end 178.2661 116.430095)
		(stroke
			(width 0.05)
			(type solid)
		)
		(layer "Edge.Cuts")
	)
	(gr_arc
		(start 178.2661 90.430095)
		(mid 179.362116 90.884079)
		(end 179.8161 91.980095)
		(stroke
			(width 0.05)
			(type solid)
		)
		(layer "Edge.Cuts")
	)
	(gr_arc
		(start 178.2661 93.530095)
		(mid 177.170084 93.076111)
		(end 176.7161 91.980095)
		(stroke
			(width 0.05)
			(type solid)
		)
		(layer "Edge.Cuts")
	)
	(gr_arc
		(start 178.2661 116.430095)
		(mid 179.362116 116.884079)
		(end 179.8161 117.980095)
		(stroke
			(width 0.05)
			(type solid)
		)
		(layer "Edge.Cuts")
	)
	(gr_arc
		(start 178.2661 119.530095)
		(mid 177.170084 119.076111)
		(end 176.7161 117.980095)
		(stroke
			(width 0.05)
			(type solid)
		)
		(layer "Edge.Cuts")
	)
	(gr_arc
		(start 179.8161 91.980095)
		(mid 179.362116 93.076111)
		(end 178.2661 93.530095)
		(stroke
			(width 0.05)
			(type solid)
		)
		(layer "Edge.Cuts")
	)
	(gr_arc
		(start 179.8161 117.980095)
		(mid 179.362116 119.076111)
		(end 178.2661 119.530095)
		(stroke
			(width 0.05)
			(type solid)
		)
		(layer "Edge.Cuts")
	)
	(gr_arc
		(start 181.0091 89.127095)
		(mid 181.772421 89.443066)
		(end 182.0891 90.206094)
		(stroke
			(width 0.05)
			(type solid)
		)
		(layer "Edge.Cuts")
	)
	(gr_line
		(start 181.068096 120.880105)
		(end 181.0681 120.880095)
		(stroke
			(width 0.05)
			(type solid)
		)
		(layer "Edge.Cuts")
	)
	(gr_line
		(start 181.0681 120.880095)
		(end 115.9601 120.876095)
		(stroke
			(width 0.05)
			(type solid)
		)
		(layer "Edge.Cuts")
	)
	(gr_arc
		(start 182.0861 119.861102)
		(mid 181.787995 120.581293)
		(end 181.068096 120.880105)
		(stroke
			(width 0.05)
			(type solid)
		)
		(layer "Edge.Cuts")
	)
	(gr_line
		(start 182.0891 90.206095)
		(end 182.0861 119.861102)
		(stroke
			(width 0.05)
			(type solid)
		)
		(layer "Edge.Cuts")
	)
	(gr_line
		(start 182.0891 90.206094)
		(end 182.0891 90.206095)
		(stroke
			(width 0.05)
			(type solid)
		)
		(layer "Edge.Cuts")
	)
	(segment
		(start 127.0183 107.479295)
		(end 127.62044 108.081435)
		(width 0.254)
		(layer "F.Cu")
		(net "NetQ1_1")
	)
	(segment
		(start 127.5151 109.476095)
		(end 127.60219 109.389005)
		(width 0.508)
		(layer "F.Cu")
		(net "NetQ1_1")
	)
	(segment
		(start 127.62044 108.638695)
		(end 127.77284 108.791095)
		(width 0.254)
		(layer "F.Cu")
		(net "NetQ1_1")
	)
	(segment
		(start 127.60219 108.816495)
		(end 127.99345 108.816495)
		(width 0.508)
		(layer "F.Cu")
		(net "NetQ1_1")
	)
	(segment
		(start 127.0183 106.360445)
		(end 127.27965 106.099095)
		(width 0.254)
		(layer "F.Cu")
		(net "NetQ1_1")
	)
	(segment
		(start 127.60219 109.389005)
		(end 127.60219 108.816495)
		(width 0.508)
		(layer "F.Cu")
		(net "NetQ1_1")
	)
	(segment
		(start 127.77284 108.791095)
		(end 127.9803 108.791095)
		(width 0.254)
		(layer "F.Cu")
		(net "NetQ1_1")
	)
	(segment
		(start 127.5151 110.476095)
		(end 127.5151 109.476095)
		(width 0.508)
		(layer "F.Cu")
		(net "NetQ1_1")
	)
	(segment
		(start 127.62044 108.638695)
		(end 127.62044 108.081435)
		(width 0.254)
		(layer "F.Cu")
		(net "NetQ1_1")
	)
	(segment
		(start 136.52755 113.676095)
		(end 137.0151 113.676095)
		(width 0.254)
		(layer "F.Cu")
		(net "NetQ1_1")
	)
	(segment
		(start 125.4151 110.476095)
		(end 127.5151 110.476095)
		(width 0.508)
		(layer "F.Cu")
		(net "NetQ1_1")
	)
	(segment
		(start 127.0183 107.479295)
		(end 127.0183 106.360445)
		(width 0.254)
		(layer "F.Cu")
		(net "NetQ1_1")
	)
	(segment
		(start 127.27965 106.099095)
		(end 128.95055 106.099095)
		(width 0.254)
		(layer "F.Cu")
		(net "NetQ1_1")
	)
	(segment
		(start 128.95055 106.099095)
		(end 136.52755 113.676095)
		(width 0.254)
		(layer "F.Cu")
		(net "NetQ1_1")
	)
	(segment
		(start 125.9151 107.876095)
		(end 125.9151 104.937745)
		(width 0.508)
		(layer "F.Cu")
		(net "NetQ1_3")
	)
	(segment
		(start 145.78765 95.777965)
		(end 145.80047 95.790775)
		(width 0.254)
		(layer "F.Cu")
		(net "VDD_USB")
	)
	(segment
		(start 145.80047 95.790775)
		(end 145.80047 95.790775)
		(width 0.254)
		(layer "F.Cu")
		(net "VDD_USB")
	)
	(segment
		(start 146.01515 99.276285)
		(end 146.01515 96.005465)
		(width 0.254)
		(layer "F.Cu")
		(net "VDD_USB")
	)
	(segment
		(start 144.3381 96.953095)
		(end 144.63815 96.953095)
		(width 0.254)
		(layer "F.Cu")
		(net "VDD_USB")
	)
	(segment
		(start 145.78765 95.777965)
		(end 145.78765 95.576095)
		(width 0.254)
		(layer "F.Cu")
		(net "VDD_USB")
	)
	(segment
		(start 144.2151 97.076095)
		(end 144.3381 96.953095)
		(width 0.254)
		(layer "F.Cu")
		(net "VDD_USB")
	)
	(segment
		(start 145.80047 95.790775)
		(end 146.01515 96.005465)
		(width 0.254)
		(layer "F.Cu")
		(net "VDD_USB")
	)
	(segment
		(start 144.63815 96.953095)
		(end 146.01515 95.576095)
		(width 0.254)
		(layer "F.Cu")
		(net "VDD_USB")
	)
	(segment
		(start 147.11497 99.276285)
		(end 147.11497 97.261315)
		(width 0.254)
		(layer "F.Cu")
		(net "USB_DP")
	)
	(segment
		(start 147.0151 97.161445)
		(end 147.11497 97.261315)
		(width 0.254)
		(layer "F.Cu")
		(net "USB_DP")
	)
	(segment
		(start 148.21479 99.276285)
		(end 148.21479 95.575845)
		(width 0.254)
		(layer "F.Cu")
		(net "USB_DM")
	)
	(segment
		(start 175.2881 98.449095)
		(end 175.97619 99.137185)
		(width 0.254)
		(layer "F.Cu")
		(net "TX_GPS")
	)
	(segment
		(start 160.3421 98.449095)
		(end 175.2881 98.449095)
		(width 0.254)
		(layer "F.Cu")
		(net "TX_GPS")
	)
	(segment
		(start 148.21479 111.475905)
		(end 148.43005 111.260645)
		(width 0.254)
		(layer "F.Cu")
		(net "TX_GPS")
	)
	(segment
		(start 148.43005 110.361145)
		(end 160.3421 98.449095)
		(width 0.254)
		(layer "F.Cu")
		(net "TX_GPS")
	)
	(segment
		(start 175.97619 100.876095)
		(end 175.97619 99.137185)
		(width 0.254)
		(layer "F.Cu")
		(net "TX_GPS")
	)
	(segment
		(start 148.43005 111.260645)
		(end 148.43005 110.361145)
		(width 0.254)
		(layer "F.Cu")
		(net "TX_GPS")
	)
	(segment
		(start 180.21752 110.340095)
		(end 180.5151 110.042515)
		(width 0.254)
		(layer "F.Cu")
		(net "TX_GPS_CONN")
	)
	(segment
		(start 180.5151 110.042515)
		(end 180.5151 105.376095)
		(width 0.254)
		(layer "F.Cu")
		(net "TX_GPS_CONN")
	)
	(segment
		(start 175.97619 101.876095)
		(end 177.0151 101.876095)
		(width 0.254)
		(layer "F.Cu")
		(net "TX_GPS_CONN")
	)
	(segment
		(start 177.0151 101.876095)
		(end 180.5151 105.376095)
		(width 0.254)
		(layer "F.Cu")
		(net "TX_GPS_CONN")
	)
	(segment
		(start 178.51611 110.340095)
		(end 180.21752 110.340095)
		(width 0.254)
		(layer "F.Cu")
		(net "TX_GPS_CONN")
	)
	(segment
		(start 178.26011 110.596095)
		(end 178.51611 110.340095)
		(width 0.508)
		(layer "F.Cu")
		(net "TX_GPS_CONN")
	)
	(segment
		(start 150.4151 99.275615)
		(end 150.4151 96.276095)
		(width 0.254)
		(layer "F.Cu")
		(net "TP1")
	)
	(segment
		(start 168.435 97.607025)
		(end 168.5151 97.607025)
		(width 0.254)
		(layer "F.Cu")
		(net "TP1")
	)
	(segment
		(start 168.5151 106.076095)
		(end 168.5151 100.076095)
		(width 0.254)
		(layer "F.Cu")
		(net "TP1")
	)
	(segment
		(start 150.41443 99.276285)
		(end 150.4151 99.275615)
		(width 0.254)
		(layer "F.Cu")
		(net "TP1")
	)
	(segment
		(start 166.2761 97.437095)
		(end 168.26506 97.437095)
		(width 0.254)
		(layer "F.Cu")
		(net "TP1")
	)
	(segment
		(start 163.0151 94.176095)
		(end 166.2761 97.437095)
		(width 0.254)
		(layer "F.Cu")
		(net "TP1")
	)
	(segment
		(start 171.03511 108.596105)
		(end 173.71011 108.596105)
		(width 0.254)
		(layer "F.Cu")
		(net "TP1")
	)
	(segment
		(start 168.26506 97.437095)
		(end 168.435 97.607025)
		(width 0.254)
		(layer "F.Cu")
		(net "TP1")
	)
	(segment
		(start 152.5151 94.176095)
		(end 163.0151 94.176095)
		(width 0.254)
		(layer "F.Cu")
		(net "TP1")
	)
	(segment
		(start 168.5151 106.076095)
		(end 171.0151 108.576095)
		(width 0.254)
		(layer "F.Cu")
		(net "TP1")
	)
	(segment
		(start 171.0151 108.576095)
		(end 171.03511 108.596105)
		(width 0.254)
		(layer "F.Cu")
		(net "TP1")
	)
	(segment
		(start 150.4151 96.276095)
		(end 152.5151 94.176095)
		(width 0.254)
		(layer "F.Cu")
		(net "TP1")
	)
	(via
		(at 168.5151 100.076095)
		(size 0.55)
		(drill 0.33)
		(layers "F.Cu" "B.Cu")
		(net "TP1")
	)
	(via
		(at 171.0151 108.576095)
		(size 0.55)
		(drill 0.33)
		(layers "F.Cu" "B.Cu")
		(net "TP1")
	)
	(via
		(at 168.5151 97.607025)
		(size 0.55)
		(drill 0.33)
		(layers "F.Cu" "B.Cu")
		(net "TP1")
	)
	(segment
		(start 168.5151 100.076095)
		(end 168.5151 97.607025)
		(width 0.254)
		(layer "B.Cu")
		(net "TP1")
	)
	(segment
		(start 145.4151 113.676095)
		(end 146.01515 113.076045)
		(width 0.254)
		(layer "F.Cu")
		(net "SDA_SPI_CS_N")
	)
	(segment
		(start 146.01515 113.076045)
		(end 146.01515 111.475905)
		(width 0.254)
		(layer "F.Cu")
		(net "SDA_SPI_CS_N")
	)
	(segment
		(start 147.1151 113.676095)
		(end 147.1151 111.476035)
		(width 0.254)
		(layer "F.Cu")
		(net "SCL_SPI_CLK")
	)
	(segment
		(start 147.11497 111.475905)
		(end 147.1151 111.476035)
		(width 0.254)
		(layer "F.Cu")
		(net "SCL_SPI_CLK")
	)
	(segment
		(start 152.61407 99.276285)
		(end 152.61407 97.597885)
		(width 0.254)
		(layer "F.Cu")
		(net "SAFEBOOT_N")
	)
	(segment
		(start 153.1151 97.096855)
		(end 153.1151 97.076095)
		(width 0.254)
		(layer "F.Cu")
		(net "SAFEBOOT_N")
	)
	(segment
		(start 152.61407 97.597885)
		(end 153.1151 97.096855)
		(width 0.254)
		(layer "F.Cu")
		(net "SAFEBOOT_N")
	)
	(segment
		(start 173.42105 100.876095)
		(end 173.42105 99.276095)
		(width 0.254)
		(layer "F.Cu")
		(net "RX_GPS")
	)
	(segment
		(start 149.58766 110.503535)
		(end 160.8151 99.276095)
		(width 0.254)
		(layer "F.Cu")
		(net "RX_GPS")
	)
	(segment
		(start 149.58766 111.202855)
		(end 149.58766 110.503535)
		(width 0.254)
		(layer "F.Cu")
		(net "RX_GPS")
	)
	(segment
		(start 160.8151 99.276095)
		(end 173.42105 99.276095)
		(width 0.254)
		(layer "F.Cu")
		(net "RX_GPS")
	)
	(segment
		(start 149.31461 111.475905)
		(end 149.58766 111.202855)
		(width 0.254)
		(layer "F.Cu")
		(net "RX_GPS")
	)
	(segment
		(start 176.0151 107.276095)
		(end 177.03911 108.300105)
		(width 0.254)
		(layer "F.Cu")
		(net "RX_GPS_CONN")
	)
	(segment
		(start 173.42105 103.082045)
		(end 176.0151 105.676095)
		(width 0.254)
		(layer "F.Cu")
		(net "RX_GPS_CONN")
	)
	(segment
		(start 173.42105 103.082045)
		(end 173.42105 101.876095)
		(width 0.254)
		(layer "F.Cu")
		(net "RX_GPS_CONN")
	)
	(segment
		(start 177.03911 108.340095)
		(end 177.03911 108.300105)
		(width 0.508)
		(layer "F.Cu")
		(net "RX_GPS_CONN")
	)
	(segment
		(start 176.0151 107.276095)
		(end 176.0151 105.676095)
		(width 0.254)
		(layer "F.Cu")
		(net "RX_GPS_CONN")
	)
	(segment
		(start 177.29511 108.596105)
		(end 178.26011 108.596105)
		(width 0.508)
		(layer "F.Cu")
		(net "RX_GPS_CONN")
	)
	(segment
		(start 177.03911 108.340095)
		(end 177.29511 108.596105)
		(width 0.508)
		(layer "F.Cu")
		(net "RX_GPS_CONN")
	)
	(segment
		(start 143.01541 99.276285)
		(end 143.01541 94.175785)
		(width 0.254)
		(layer "F.Cu")
		(net "RST_GPS")
	)
	(segment
		(start 167.2151 106.776095)
		(end 171.0151 110.576095)
		(width 0.254)
		(layer "F.Cu")
		(net "RST_GPS")
	)
	(segment
		(start 143.01541 94.175785)
		(end 143.5151 93.676095)
		(width 0.254)
		(layer "F.Cu")
		(net "RST_GPS")
	)
	(segment
		(start 167.2151 106.776095)
		(end 167.2151 100.072155)
		(width 0.254)
		(layer "F.Cu")
		(net "RST_GPS")
	)
	(segment
		(start 143.5151 93.676095)
		(end 164.21161 93.676095)
		(width 0.254)
		(layer "F.Cu")
		(net "RST_GPS")
	)
	(segment
		(start 171.0151 110.576095)
		(end 173.6901 110.576095)
		(width 0.254)
		(layer "F.Cu")
		(net "RST_GPS")
	)
	(segment
		(start 164.21161 93.676095)
		(end 167.21161 96.676095)
		(width 0.254)
		(layer "F.Cu")
		(net "RST_GPS")
	)
	(segment
		(start 173.6901 110.576095)
		(end 173.71011 110.596095)
		(width 0.254)
		(layer "F.Cu")
		(net "RST_GPS")
	)
	(via
		(at 167.2151 100.072155)
		(size 0.55)
		(drill 0.33)
		(layers "F.Cu" "B.Cu")
		(net "RST_GPS")
	)
	(via
		(at 171.0151 110.576095)
		(size 0.55)
		(drill 0.33)
		(layers "F.Cu" "B.Cu")
		(net "RST_GPS")
	)
	(via
		(at 167.21161 96.676095)
		(size 0.55)
		(drill 0.33)
		(layers "F.Cu" "B.Cu")
		(net "RST_GPS")
	)
	(segment
		(start 167.21161 96.676095)
		(end 167.21335 96.677835)
		(width 0.254)
		(layer "B.Cu")
		(net "RST_GPS")
	)
	(segment
		(start 167.21335 100.070415)
		(end 167.21335 96.677835)
		(width 0.254)
		(layer "B.Cu")
		(net "RST_GPS")
	)
	(segment
		(start 167.21335 100.070415)
		(end 167.2151 100.072155)
		(width 0.254)
		(layer "B.Cu")
		(net "RST_GPS")
	)
	(segment
		(start 139.71595 99.276285)
		(end 139.71595 96.976095)
		(width 0.1778)
		(layer "F.Cu")
		(net "RF_MODULE")
	)
	(segment
		(start 130.35991 100.332135)
		(end 133.972 96.720045)
		(width 0.1778)
		(layer "F.Cu")
		(net "RF_ANT")
	)
	(segment
		(start 135.76805 95.976095)
		(end 139.71595 95.976095)
		(width 0.1778)
		(layer "F.Cu")
		(net "RF_ANT")
	)
	(segment
		(start 120.70511 101.076085)
		(end 128.56386 101.076085)
		(width 0.1778)
		(layer "F.Cu")
		(net "RF_ANT")
	)
	(arc
		(start 133.971999 96.720044)
		(mid 134.796034 96.169441)
		(end 135.76805 95.976095)
		(width 0.1778)
		(layer "F.Cu")
		(net "RF_ANT")
	)
	(arc
		(start 130.359911 100.332136)
		(mid 129.535876 100.882739)
		(end 128.56386 101.076085)
		(width 0.1778)
		(layer "F.Cu")
		(net "RF_ANT")
	)
	(segment
		(start 165.96429 109.651495)
		(end 166.11029 109.505495)
		(width 0.508)
		(layer "F.Cu")
		(net "NetLED2_2")
	)
	(segment
		(start 166.37847 109.505495)
		(end 166.40787 109.476095)
		(width 0.508)
		(layer "F.Cu")
		(net "NetLED2_2")
	)
	(segment
		(start 166.40787 109.476095)
		(end 167.7151 109.476095)
		(width 0.508)
		(layer "F.Cu")
		(net "NetLED2_2")
	)
	(segment
		(start 166.11029 109.505495)
		(end 166.37847 109.505495)
		(width 0.508)
		(layer "F.Cu")
		(net "NetLED2_2")
	)
	(segment
		(start 159.2103 109.505495)
		(end 159.47848 109.505495)
		(width 0.508)
		(layer "F.Cu")
		(net "NetLED1_2")
	)
	(segment
		(start 159.50788 109.476095)
		(end 160.8151 109.476095)
		(width 0.508)
		(layer "F.Cu")
		(net "NetLED1_2")
	)
	(segment
		(start 159.0643 109.651495)
		(end 159.2103 109.505495)
		(width 0.508)
		(layer "F.Cu")
		(net "NetLED1_2")
	)
	(segment
		(start 159.47848 109.505495)
		(end 159.50788 109.476095)
		(width 0.508)
		(layer "F.Cu")
		(net "NetLED1_2")
	)
	(segment
		(start 125.7191 103.391745)
		(end 125.7191 103.110505)
		(width 0.508)
		(layer "F.Cu")
		(net "NetC5_2")
	)
	(segment
		(start 125.70276 103.094165)
		(end 125.70276 101.876095)
		(width 0.508)
		(layer "F.Cu")
		(net "NetC5_2")
	)
	(segment
		(start 125.70276 103.094165)
		(end 125.7191 103.110505)
		(width 0.508)
		(layer "F.Cu")
		(net "NetC5_2")
	)
	(segment
		(start 125.7651 103.437745)
		(end 125.9151 103.437745)
		(width 0.508)
		(layer "F.Cu")
		(net "NetC5_2")
	)
	(segment
		(start 125.7191 103.391745)
		(end 125.7651 103.437745)
		(width 0.508)
		(layer "F.Cu")
		(net "NetC5_2")
	)
	(segment
		(start 125.9151 103.437745)
		(end 127.65344 103.437745)
		(width 0.508)
		(layer "F.Cu")
		(net "NetC5_2")
	)
	(segment
		(start 138.0151 113.676095)
		(end 138.0151 113.676095)
		(width 0.254)
		(layer "F.Cu")
		(net "LNA_EN")
	)
	(segment
		(start 139.7151 113.676095)
		(end 139.71595 113.675245)
		(width 0.254)
		(layer "F.Cu")
		(net "LNA_EN")
	)
	(segment
		(start 139.71595 113.675245)
		(end 139.71595 111.475905)
		(width 0.254)
		(layer "F.Cu")
		(net "LNA_EN")
	)
	(segment
		(start 138.0151 113.676095)
		(end 139.7151 113.676095)
		(width 0.254)
		(layer "F.Cu")
		(net "LNA_EN")
	)
	(segment
		(start 117.14928 102.295375)
		(end 119.06383 102.295375)
		(width 0.0127)
		(layer "F.Cu")
		(net "GND")
	)
	(segment
		(start 122.34673 99.856975)
		(end 124.26128 99.856975)
		(width 0.0127)
		(layer "F.Cu")
		(net "GND")
	)
	(segment
		(start 117.14928 104.657575)
		(end 124.26128 104.657575)
		(width 0.0127)
		(layer "F.Cu")
		(net "GND")
	)
	(segment
		(start 117.14928 99.856975)
		(end 119.06383 99.856975)
		(width 0.0127)
		(layer "F.Cu")
		(net "GND")
	)
	(segment
		(start 124.26128 104.657575)
		(end 124.26128 102.295375)
		(width 0.0127)
		(layer "F.Cu")
		(net "GND")
	)
	(segment
		(start 170.9351 106.596095)
		(end 173.71011 106.596095)
		(width 0.508)
		(layer "F.Cu")
		(net "GND")
	)
	(segment
		(start 117.14928 104.657575)
		(end 117.14928 102.295375)
		(width 0.0127)
		(layer "F.Cu")
		(net "GND")
	)
	(segment
		(start 117.14928 99.856975)
		(end 117.14928 97.494775)
		(width 0.0127)
		(layer "F.Cu")
		(net "GND")
	)
	(segment
		(start 122.34673 102.295375)
		(end 124.26128 102.295375)
		(width 0.0127)
		(layer "F.Cu")
		(net "GND")
	)
	(segment
		(start 170.9151 106.576095)
		(end 170.9351 106.596095)
		(width 0.508)
		(layer "F.Cu")
		(net "GND")
	)
	(segment
		(start 117.14928 97.494775)
		(end 124.26128 97.494775)
		(width 0.0127)
		(layer "F.Cu")
		(net "GND")
	)
	(segment
		(start 124.26128 99.856975)
		(end 124.26128 97.494775)
		(width 0.0127)
		(layer "F.Cu")
		(net "GND")
	)
	(via
		(at 152.7991 115.636095)
		(size 0.5588)
		(drill 0.3302)
		(layers "F.Cu" "B.Cu")
		(tenting
			(front yes)
			(back yes)
		)
		(net "GND")
	)
	(via
		(at 162.9591 115.636095)
		(size 0.5588)
		(drill 0.3302)
		(layers "F.Cu" "B.Cu")
		(tenting
			(front yes)
			(back yes)
		)
		(net "GND")
	)
	(via
		(at 170.5791 102.936095)
		(size 0.5588)
		(drill 0.3302)
		(layers "F.Cu" "B.Cu")
		(tenting
			(front yes)
			(back yes)
		)
		(net "GND")
	)
	(via
		(at 170.5791 95.316095)
		(size 0.5588)
		(drill 0.3302)
		(layers "F.Cu" "B.Cu")
		(tenting
			(front yes)
			(back yes)
		)
		(net "GND")
	)
	(via
		(at 178.1991 105.476095)
		(size 0.5588)
		(drill 0.3302)
		(layers "F.Cu" "B.Cu")
		(tenting
			(front yes)
			(back yes)
		)
		(net "GND")
	)
	(via
		(at 132.4791 102.936095)
		(size 0.5588)
		(drill 0.3302)
		(layers "F.Cu" "B.Cu")
		(tenting
			(front yes)
			(back yes)
		)
		(net "GND")
	)
	(via
		(at 129.9391 113.096095)
		(size 0.5588)
		(drill 0.3302)
		(layers "F.Cu" "B.Cu")
		(tenting
			(front yes)
			(back yes)
		)
		(net "GND")
	)
	(via
		(at 119.7791 115.636095)
		(size 0.5588)
		(drill 0.3302)
		(layers "F.Cu" "B.Cu")
		(tenting
			(front yes)
			(back yes)
		)
		(net "GND")
	)
	(via
		(at 122.3191 110.556095)
		(size 0.5588)
		(drill 0.3302)
		(layers "F.Cu" "B.Cu")
		(tenting
			(front yes)
			(back yes)
		)
		(net "GND")
	)
	(via
		(at 137.5591 100.396095)
		(size 0.5588)
		(drill 0.3302)
		(layers "F.Cu" "B.Cu")
		(tenting
			(front yes)
			(back yes)
		)
		(net "GND")
	)
	(via
		(at 127.3991 92.776095)
		(size 0.5588)
		(drill 0.3302)
		(layers "F.Cu" "B.Cu")
		(tenting
			(front yes)
			(back yes)
		)
		(net "GND")
	)
	(via
		(at 132.83966 98.673375)
		(size 0.55)
		(drill 0.3)
		(layers "F.Cu" "B.Cu")
		(tenting
			(front yes)
			(back yes)
		)
		(net "GND")
	)
	(via
		(at 165.4991 100.396095)
		(size 0.5588)
		(drill 0.3302)
		(layers "F.Cu" "B.Cu")
		(tenting
			(front yes)
			(back yes)
		)
		(net "GND")
	)
	(via
		(at 132.09154 99.421495)
		(size 0.55)
		(drill 0.3)
		(layers "F.Cu" "B.Cu")
		(tenting
			(front yes)
			(back yes)
		)
		(net "GND")
	)
	(via
		(at 135.0191 115.636095)
		(size 0.5588)
		(drill 0.3302)
		(layers "F.Cu" "B.Cu")
		(tenting
			(front yes)
			(back yes)
		)
		(net "GND")
	)
	(via
		(at 157.8791 105.476095)
		(size 0.5588)
		(drill 0.3302)
		(layers "F.Cu" "B.Cu")
		(tenting
			(front yes)
			(back yes)
		)
		(net "GND")
	)
	(via
		(at 147.7191 92.776095)
		(size 0.5588)
		(drill 0.3302)
		(layers "F.Cu" "B.Cu")
		(tenting
			(front yes)
			(back yes)
		)
		(net "GND")
	)
	(via
		(at 119.7791 110.556095)
		(size 0.5588)
		(drill 0.3302)
		(layers "F.Cu" "B.Cu")
		(tenting
			(front yes)
			(back yes)
		)
		(net "GND")
	)
	(via
		(at 132.4791 105.476095)
		(size 0.5588)
		(drill 0.3302)
		(layers "F.Cu" "B.Cu")
		(tenting
			(front yes)
			(back yes)
		)
		(net "GND")
	)
	(via
		(at 135.24338 96.633225)
		(size 0.55)
		(drill 0.3)
		(layers "F.Cu" "B.Cu")
		(tenting
			(front yes)
			(back yes)
		)
		(net "GND")
	)
	(via
		(at 155.3391 100.396095)
		(size 0.5588)
		(drill 0.3302)
		(layers "F.Cu" "B.Cu")
		(tenting
			(front yes)
			(back yes)
		)
		(net "GND")
	)
	(via
		(at 157.8791 97.856095)
		(size 0.5588)
		(drill 0.3302)
		(layers "F.Cu" "B.Cu")
		(tenting
			(front yes)
			(back yes)
		)
		(net "GND")
	)
	(via
		(at 140.43602 96.297625)
		(size 0.55)
		(drill 0.3)
		(layers "F.Cu" "B.Cu")
		(tenting
			(front yes)
			(back yes)
		)
		(net "GND")
	)
	(via
		(at 178.1991 95.316095)
		(size 0.5588)
		(drill 0.3302)
		(layers "F.Cu" "B.Cu")
		(tenting
			(front yes)
			(back yes)
		)
		(net "GND")
	)
	(via
		(at 130.16158 99.709475)
		(size 0.55)
		(drill 0.3)
		(layers "F.Cu" "B.Cu")
		(tenting
			(front yes)
			(back yes)
		)
		(net "GND")
	)
	(via
		(at 117.2391 115.636095)
		(size 0.5588)
		(drill 0.3302)
		(layers "F.Cu" "B.Cu")
		(tenting
			(front yes)
			(back yes)
		)
		(net "GND")
	)
	(via
		(at 135.92817 95.395565)
		(size 0.55)
		(drill 0.3)
		(layers "F.Cu" "B.Cu")
		(tenting
			(front yes)
			(back yes)
		)
		(net "GND")
	)
	(via
		(at 128.27065 100.495555)
		(size 0.55)
		(drill 0.3)
		(layers "F.Cu" "B.Cu")
		(tenting
			(front yes)
			(back yes)
		)
		(net "GND")
	)
	(via
		(at 140.0991 102.936095)
		(size 0.5588)
		(drill 0.3302)
		(layers "F.Cu" "B.Cu")
		(tenting
			(front yes)
			(back yes)
		)
		(net "GND")
	)
	(via
		(at 127.3991 95.316095)
		(size 0.5588)
		(drill 0.3302)
		(layers "F.Cu" "B.Cu")
		(tenting
			(front yes)
			(back yes)
		)
		(net "GND")
	)
	(via
		(at 122.3191 108.016095)
		(size 0.5588)
		(drill 0.3302)
		(layers "F.Cu" "B.Cu")
		(tenting
			(front yes)
			(back yes)
		)
		(net "GND")
	)
	(via
		(at 150.2591 102.936095)
		(size 0.5588)
		(drill 0.3302)
		(layers "F.Cu" "B.Cu")
		(tenting
			(front yes)
			(back yes)
		)
		(net "GND")
	)
	(via
		(at 142.6391 113.096095)
		(size 0.5588)
		(drill 0.3302)
		(layers "F.Cu" "B.Cu")
		(tenting
			(front yes)
			(back yes)
		)
		(net "GND")
	)
	(via
		(at 139.10216 95.395565)
		(size 0.55)
		(drill 0.3)
		(layers "F.Cu" "B.Cu")
		(tenting
			(front yes)
			(back yes)
		)
		(net "GND")
	)
	(via
		(at 178.1991 97.856095)
		(size 0.5588)
		(drill 0.3302)
		(layers "F.Cu" "B.Cu")
		(tenting
			(front yes)
			(back yes)
		)
		(net "GND")
	)
	(via
		(at 137.5591 92.776095)
		(size 0.5588)
		(drill 0.3302)
		(layers "F.Cu" "B.Cu")
		(tenting
			(front yes)
			(back yes)
		)
		(net "GND")
	)
	(via
		(at 130.9097 98.961355)
		(size 0.55)
		(drill 0.3)
		(layers "F.Cu" "B.Cu")
		(tenting
			(front yes)
			(back yes)
		)
		(net "GND")
	)
	(via
		(at 135.0191 118.176095)
		(size 0.5588)
		(drill 0.3302)
		(layers "F.Cu" "B.Cu")
		(tenting
			(front yes)
			(back yes)
		)
		(net "GND")
	)
	(via
		(at 132.4791 118.176095)
		(size 0.5588)
		(drill 0.3302)
		(layers "F.Cu" "B.Cu")
		(tenting
			(front yes)
			(back yes)
		)
		(net "GND")
	)
	(via
		(at 155.3391 115.636095)
		(size 0.5588)
		(drill 0.3302)
		(layers "F.Cu" "B.Cu")
		(tenting
			(front yes)
			(back yes)
		)
		(net "GND")
	)
	(via
		(at 155.3391 113.096095)
		(size 0.5588)
		(drill 0.3302)
		(layers "F.Cu" "B.Cu")
		(tenting
			(front yes)
			(back yes)
		)
		(net "GND")
	)
	(via
		(at 162.9591 95.316095)
		(size 0.5588)
		(drill 0.3302)
		(layers "F.Cu" "B.Cu")
		(tenting
			(front yes)
			(back yes)
		)
		(net "GND")
	)
	(via
		(at 122.3191 102.936095)
		(size 0.5588)
		(drill 0.3302)
		(layers "F.Cu" "B.Cu")
		(tenting
			(front yes)
			(back yes)
		)
		(net "GND")
	)
	(via
		(at 137.5591 102.936095)
		(size 0.5588)
		(drill 0.3302)
		(layers "F.Cu" "B.Cu")
		(tenting
			(front yes)
			(back yes)
		)
		(net "GND")
	)
	(via
		(at 121.92557 100.483395)
		(size 0.55)
		(drill 0.3)
		(layers "F.Cu" "B.Cu")
		(tenting
			(front yes)
			(back yes)
		)
		(net "GND")
	)
	(via
		(at 178.1991 115.636095)
		(size 0.5588)
		(drill 0.3302)
		(layers "F.Cu" "B.Cu")
		(tenting
			(front yes)
			(back yes)
		)
		(net "GND")
	)
	(via
		(at 137.5591 108.016095)
		(size 0.5588)
		(drill 0.3302)
		(layers "F.Cu" "B.Cu")
		(tenting
			(front yes)
			(back yes)
		)
		(net "GND")
	)
	(via
		(at 119.7791 95.316095)
		(size 0.5588)
		(drill 0.3302)
		(layers "F.Cu" "B.Cu")
		(tenting
			(front yes)
			(back yes)
		)
		(net "GND")
	)
	(via
		(at 168.0391 115.636095)
		(size 0.5588)
		(drill 0.3302)
		(layers "F.Cu" "B.Cu")
		(tenting
			(front yes)
			(back yes)
		)
		(net "GND")
	)
	(via
		(at 145.1791 102.936095)
		(size 0.5588)
		(drill 0.3302)
		(layers "F.Cu" "B.Cu")
		(tenting
			(front yes)
			(back yes)
		)
		(net "GND")
	)
	(via
		(at 170.5791 100.396095)
		(size 0.5588)
		(drill 0.3302)
		(layers "F.Cu" "B.Cu")
		(tenting
			(front yes)
			(back yes)
		)
		(net "GND")
	)
	(via
		(at 145.1791 115.636095)
		(size 0.5588)
		(drill 0.3302)
		(layers "F.Cu" "B.Cu")
		(tenting
			(front yes)
			(back yes)
		)
		(net "GND")
	)
	(via
		(at 137.5591 118.176095)
		(size 0.5588)
		(drill 0.3302)
		(layers "F.Cu" "B.Cu")
		(tenting
			(front yes)
			(back yes)
		)
		(net "GND")
	)
	(via
		(at 132.4791 100.396095)
		(size 0.5588)
		(drill 0.3302)
		(layers "F.Cu" "B.Cu")
		(tenting
			(front yes)
			(back yes)
		)
		(net "GND")
	)
	(via
		(at 127.3991 113.096095)
		(size 0.5588)
		(drill 0.3302)
		(layers "F.Cu" "B.Cu")
		(tenting
			(front yes)
			(back yes)
		)
		(net "GND")
	)
	(via
		(at 135.0191 108.016095)
		(size 0.5588)
		(drill 0.3302)
		(layers "F.Cu" "B.Cu")
		(tenting
			(front yes)
			(back yes)
		)
		(net "GND")
	)
	(via
		(at 117.2391 108.016095)
		(size 0.5588)
		(drill 0.3302)
		(layers "F.Cu" "B.Cu")
		(tenting
			(front yes)
			(back yes)
		)
		(net "GND")
	)
	(via
		(at 137.3566 96.556625)
		(size 0.55)
		(drill 0.3)
		(layers "F.Cu" "B.Cu")
		(tenting
			(front yes)
			(back yes)
		)
		(net "GND")
	)
	(via
		(at 122.9835 100.495555)
		(size 0.55)
		(drill 0.3)
		(layers "F.Cu" "B.Cu")
		(tenting
			(front yes)
			(back yes)
		)
		(net "GND")
	)
	(via
		(at 145.1791 97.856095)
		(size 0.5588)
		(drill 0.3302)
		(layers "F.Cu" "B.Cu")
		(tenting
			(front yes)
			(back yes)
		)
		(net "GND")
	)
	(via
		(at 147.7191 105.476095)
		(size 0.5588)
		(drill 0.3302)
		(layers "F.Cu" "B.Cu")
		(tenting
			(front yes)
			(back yes)
		)
		(net "GND")
	)
	(via
		(at 124.8591 118.176095)
		(size 0.5588)
		(drill 0.3302)
		(layers "F.Cu" "B.Cu")
		(tenting
			(front yes)
			(back yes)
		)
		(net "GND")
	)
	(via
		(at 131.65781 98.213235)
		(size 0.55)
		(drill 0.3)
		(layers "F.Cu" "B.Cu")
		(tenting
			(front yes)
			(back yes)
		)
		(net "GND")
	)
	(via
		(at 137.5591 105.476095)
		(size 0.5588)
		(drill 0.3302)
		(layers "F.Cu" "B.Cu")
		(tenting
			(front yes)
			(back yes)
		)
		(net "GND")
	)
	(via
		(at 119.7791 105.476095)
		(size 0.5588)
		(drill 0.3302)
		(layers "F.Cu" "B.Cu")
		(tenting
			(front yes)
			(back yes)
		)
		(net "GND")
	)
	(via
		(at 117.2391 110.556095)
		(size 0.5588)
		(drill 0.3302)
		(layers "F.Cu" "B.Cu")
		(tenting
			(front yes)
			(back yes)
		)
		(net "GND")
	)
	(via
		(at 155.3391 97.856095)
		(size 0.5588)
		(drill 0.3302)
		(layers "F.Cu" "B.Cu")
		(tenting
			(front yes)
			(back yes)
		)
		(net "GND")
	)
	(via
		(at 142.6391 105.476095)
		(size 0.5588)
		(drill 0.3302)
		(layers "F.Cu" "B.Cu")
		(tenting
			(front yes)
			(back yes)
		)
		(net "GND")
	)
	(via
		(at 162.9591 102.936095)
		(size 0.5588)
		(drill 0.3302)
		(layers "F.Cu" "B.Cu")
		(tenting
			(front yes)
			(back yes)
		)
		(net "GND")
	)
	(via
		(at 155.3391 92.776095)
		(size 0.5588)
		(drill 0.3302)
		(layers "F.Cu" "B.Cu")
		(tenting
			(front yes)
			(back yes)
		)
		(net "GND")
	)
	(via
		(at 127.3991 118.176095)
		(size 0.5588)
		(drill 0.3302)
		(layers "F.Cu" "B.Cu")
		(tenting
			(front yes)
			(back yes)
		)
		(net "GND")
	)
	(via
		(at 121.12979 99.786185)
		(size 0.55)
		(drill 0.3)
		(layers "F.Cu" "B.Cu")
		(tenting
			(front yes)
			(back yes)
		)
		(net "GND")
	)
	(via
		(at 140.15128 95.278655)
		(size 0.55)
		(drill 0.3)
		(layers "F.Cu" "B.Cu")
		(tenting
			(front yes)
			(back yes)
		)
		(net "GND")
	)
	(via
		(at 155.3391 108.016095)
		(size 0.5588)
		(drill 0.3302)
		(layers "F.Cu" "B.Cu")
		(tenting
			(front yes)
			(back yes)
		)
		(net "GND")
	)
	(via
		(at 155.3391 95.316095)
		(size 0.5588)
		(drill 0.3302)
		(layers "F.Cu" "B.Cu")
		(tenting
			(front yes)
			(back yes)
		)
		(net "GND")
	)
	(via
		(at 135.0191 110.556095)
		(size 0.5588)
		(drill 0.3302)
		(layers "F.Cu" "B.Cu")
		(tenting
			(front yes)
			(back yes)
		)
		(net "GND")
	)
	(via
		(at 175.6591 102.936095)
		(size 0.5588)
		(drill 0.3302)
		(layers "F.Cu" "B.Cu")
		(tenting
			(front yes)
			(back yes)
		)
		(net "GND")
	)
	(via
		(at 129.67378 101.446045)
		(size 0.55)
		(drill 0.3)
		(layers "F.Cu" "B.Cu")
		(tenting
			(front yes)
			(back yes)
		)
		(net "GND")
	)
	(via
		(at 134.87849 95.527995)
		(size 0.55)
		(drill 0.3)
		(layers "F.Cu" "B.Cu")
		(tenting
			(front yes)
			(back yes)
		)
		(net "GND")
	)
	(via
		(at 127.21265 100.495555)
		(size 0.55)
		(drill 0.3)
		(layers "F.Cu" "B.Cu")
		(tenting
			(front yes)
			(back yes)
		)
		(net "GND")
	)
	(via
		(at 178.1991 100.396095)
		(size 0.5588)
		(drill 0.3302)
		(layers "F.Cu" "B.Cu")
		(tenting
			(front yes)
			(back yes)
		)
		(net "GND")
	)
	(via
		(at 129.9391 118.176095)
		(size 0.5588)
		(drill 0.3302)
		(layers "F.Cu" "B.Cu")
		(tenting
			(front yes)
			(back yes)
		)
		(net "GND")
	)
	(via
		(at 122.29848 101.656615)
		(size 0.55)
		(drill 0.3)
		(layers "F.Cu" "B.Cu")
		(tenting
			(front yes)
			(back yes)
		)
		(net "GND")
	)
	(via
		(at 147.7191 115.636095)
		(size 0.5588)
		(drill 0.3302)
		(layers "F.Cu" "B.Cu")
		(tenting
			(front yes)
			(back yes)
		)
		(net "GND")
	)
	(via
		(at 157.8791 92.776095)
		(size 0.5588)
		(drill 0.3302)
		(layers "F.Cu" "B.Cu")
		(tenting
			(front yes)
			(back yes)
		)
		(net "GND")
	)
	(via
		(at 127.57827 101.656615)
		(size 0.55)
		(drill 0.3)
		(layers "F.Cu" "B.Cu")
		(tenting
			(front yes)
			(back yes)
		)
		(net "GND")
	)
	(via
		(at 145.1791 105.476095)
		(size 0.5588)
		(drill 0.3302)
		(layers "F.Cu" "B.Cu")
		(tenting
			(front yes)
			(back yes)
		)
		(net "GND")
	)
	(via
		(at 150.2591 92.776095)
		(size 0.5588)
		(drill 0.3302)
		(layers "F.Cu" "B.Cu")
		(tenting
			(front yes)
			(back yes)
		)
		(net "GND")
	)
	(via
		(at 160.4191 92.776095)
		(size 0.5588)
		(drill 0.3302)
		(layers "F.Cu" "B.Cu")
		(tenting
			(front yes)
			(back yes)
		)
		(net "GND")
	)
	(via
		(at 147.7191 102.936095)
		(size 0.5588)
		(drill 0.3302)
		(layers "F.Cu" "B.Cu")
		(tenting
			(front yes)
			(back yes)
		)
		(net "GND")
	)
	(via
		(at 129.9391 92.776095)
		(size 0.5588)
		(drill 0.3302)
		(layers "F.Cu" "B.Cu")
		(tenting
			(front yes)
			(back yes)
		)
		(net "GND")
	)
	(via
		(at 117.2391 95.316095)
		(size 0.5588)
		(drill 0.3302)
		(layers "F.Cu" "B.Cu")
		(tenting
			(front yes)
			(back yes)
		)
		(net "GND")
	)
	(via
		(at 122.3191 115.636095)
		(size 0.5588)
		(drill 0.3302)
		(layers "F.Cu" "B.Cu")
		(tenting
			(front yes)
			(back yes)
		)
		(net "GND")
	)
	(via
		(at 155.31799 110.534985)
		(size 0.5588)
		(drill 0.3302)
		(layers "F.Cu" "B.Cu")
		(tenting
			(front yes)
			(back yes)
		)
		(net "GND")
	)
	(via
		(at 142.6391 115.636095)
		(size 0.5588)
		(drill 0.3302)
		(layers "F.Cu" "B.Cu")
		(tenting
			(front yes)
			(back yes)
		)
		(net "GND")
	)
	(via
		(at 175.6591 118.176095)
		(size 0.5588)
		(drill 0.3302)
		(layers "F.Cu" "B.Cu")
		(tenting
			(front yes)
			(back yes)
		)
		(net "GND")
	)
	(via
		(at 145.1791 108.016095)
		(size 0.5588)
		(drill 0.3302)
		(layers "F.Cu" "B.Cu")
		(tenting
			(front yes)
			(back yes)
		)
		(net "GND")
	)
	(via
		(at 157.8791 113.096095)
		(size 0.5588)
		(drill 0.3302)
		(layers "F.Cu" "B.Cu")
		(tenting
			(front yes)
			(back yes)
		)
		(net "GND")
	)
	(via
		(at 132.4791 95.316095)
		(size 0.5588)
		(drill 0.3302)
		(layers "F.Cu" "B.Cu")
		(tenting
			(front yes)
			(back yes)
		)
		(net "GND")
	)
	(via
		(at 117.2391 113.096095)
		(size 0.5588)
		(drill 0.3302)
		(layers "F.Cu" "B.Cu")
		(tenting
			(front yes)
			(back yes)
		)
		(net "GND")
	)
	(via
		(at 162.9591 108.016095)
		(size 0.5588)
		(drill 0.3302)
		(layers "F.Cu" "B.Cu")
		(tenting
			(front yes)
			(back yes)
		)
		(net "GND")
	)
	(via
		(at 145.1791 92.776095)
		(size 0.5588)
		(drill 0.3302)
		(layers "F.Cu" "B.Cu")
		(tenting
			(front yes)
			(back yes)
		)
		(net "GND")
	)
	(via
		(at 132.4791 108.016095)
		(size 0.5588)
		(drill 0.3302)
		(layers "F.Cu" "B.Cu")
		(tenting
			(front yes)
			(back yes)
		)
		(net "GND")
	)
	(via
		(at 135.0191 100.396095)
		(size 0.5588)
		(drill 0.3302)
		(layers "F.Cu" "B.Cu")
		(tenting
			(front yes)
			(back yes)
		)
		(net "GND")
	)
	(via
		(at 173.1191 95.316095)
		(size 0.5588)
		(drill 0.3302)
		(layers "F.Cu" "B.Cu")
		(tenting
			(front yes)
			(back yes)
		)
		(net "GND")
	)
	(via
		(at 168.0391 92.776095)
		(size 0.5588)
		(drill 0.3302)
		(layers "F.Cu" "B.Cu")
		(tenting
			(front yes)
			(back yes)
		)
		(net "GND")
	)
	(via
		(at 160.4191 95.316095)
		(size 0.5588)
		(drill 0.3302)
		(layers "F.Cu" "B.Cu")
		(tenting
			(front yes)
			(back yes)
		)
		(net "GND")
	)
	(via
		(at 173.1191 92.776095)
		(size 0.5588)
		(drill 0.3302)
		(layers "F.Cu" "B.Cu")
		(tenting
			(front yes)
			(back yes)
		)
		(net "GND")
	)
	(via
		(at 162.9591 105.476095)
		(size 0.5588)
		(drill 0.3302)
		(layers "F.Cu" "B.Cu")
		(tenting
			(front yes)
			(back yes)
		)
		(net "GND")
	)
	(via
		(at 160.4191 108.016095)
		(size 0.5588)
		(drill 0.3302)
		(layers "F.Cu" "B.Cu")
		(tenting
			(front yes)
			(back yes)
		)
		(net "GND")
	)
	(via
		(at 136.29861 96.556625)
		(size 0.55)
		(drill 0.3)
		(layers "F.Cu" "B.Cu")
		(tenting
			(front yes)
			(back yes)
		)
		(net "GND")
	)
	(via
		(at 165.4991 92.776095)
		(size 0.5588)
		(drill 0.3302)
		(layers "F.Cu" "B.Cu")
		(tenting
			(front yes)
			(back yes)
		)
		(net "GND")
	)
	(via
		(at 120.36486 102.386885)
		(size 0.55)
		(drill 0.3)
		(layers "F.Cu" "B.Cu")
		(tenting
			(front yes)
			(back yes)
		)
		(net "GND")
	)
	(via
		(at 122.3191 92.776095)
		(size 0.5588)
		(drill 0.3302)
		(layers "F.Cu" "B.Cu")
		(tenting
			(front yes)
			(back yes)
		)
		(net "GND")
	)
	(via
		(at 136.98617 95.395565)
		(size 0.55)
		(drill 0.3)
		(layers "F.Cu" "B.Cu")
		(tenting
			(front yes)
			(back yes)
		)
		(net "GND")
	)
	(via
		(at 160.4191 102.936095)
		(size 0.5588)
		(drill 0.3302)
		(layers "F.Cu" "B.Cu")
		(tenting
			(front yes)
			(back yes)
		)
		(net "GND")
	)
	(via
		(at 127.3991 97.856095)
		(size 0.5588)
		(drill 0.3302)
		(layers "F.Cu" "B.Cu")
		(tenting
			(front yes)
			(back yes)
		)
		(net "GND")
	)
	(via
		(at 124.8591 105.476095)
		(size 0.5588)
		(drill 0.3302)
		(layers "F.Cu" "B.Cu")
		(tenting
			(front yes)
			(back yes)
		)
		(net "GND")
	)
	(via
		(at 132.4791 113.096095)
		(size 0.5588)
		(drill 0.3302)
		(layers "F.Cu" "B.Cu")
		(tenting
			(front yes)
			(back yes)
		)
		(net "GND")
	)
	(via
		(at 120.07534 99.872765)
		(size 0.55)
		(drill 0.3)
		(layers "F.Cu" "B.Cu")
		(tenting
			(front yes)
			(back yes)
		)
		(net "GND")
	)
	(via
		(at 124.8591 92.776095)
		(size 0.5588)
		(drill 0.3302)
		(layers "F.Cu" "B.Cu")
		(tenting
			(front yes)
			(back yes)
		)
		(net "GND")
	)
	(via
		(at 157.8791 108.016095)
		(size 0.5588)
		(drill 0.3302)
		(layers "F.Cu" "B.Cu")
		(tenting
			(front yes)
			(back yes)
		)
		(net "GND")
	)
	(via
		(at 170.5791 115.636095)
		(size 0.5588)
		(drill 0.3302)
		(layers "F.Cu" "B.Cu")
		(tenting
			(front yes)
			(back yes)
		)
		(net "GND")
	)
	(via
		(at 175.6591 115.636095)
		(size 0.5588)
		(drill 0.3302)
		(layers "F.Cu" "B.Cu")
		(tenting
			(front yes)
			(back yes)
		)
		(net "GND")
	)
	(via
		(at 128.63626 101.653215)
		(size 0.55)
		(drill 0.3)
		(layers "F.Cu" "B.Cu")
		(tenting
			(front yes)
			(back yes)
		)
		(net "GND")
	)
	(via
		(at 175.6591 97.856095)
		(size 0.5588)
		(drill 0.3302)
		(layers "F.Cu" "B.Cu")
		(tenting
			(front yes)
			(back yes)
		)
		(net "GND")
	)
	(via
		(at 160.4191 105.476095)
		(size 0.5588)
		(drill 0.3302)
		(layers "F.Cu" "B.Cu")
		(tenting
			(front yes)
			(back yes)
		)
		(net "GND")
	)
	(via
		(at 165.4991 108.016095)
		(size 0.5588)
		(drill 0.3302)
		(layers "F.Cu" "B.Cu")
		(tenting
			(front yes)
			(back yes)
		)
		(net "GND")
	)
	(via
		(at 126.52027 101.656615)
		(size 0.55)
		(drill 0.3)
		(layers "F.Cu" "B.Cu")
		(tenting
			(front yes)
			(back yes)
		)
		(net "GND")
	)
	(via
		(at 117.2391 105.476095)
		(size 0.5588)
		(drill 0.3302)
		(layers "F.Cu" "B.Cu")
		(tenting
			(front yes)
			(back yes)
		)
		(net "GND")
	)
	(via
		(at 129.9391 105.476095)
		(size 0.5588)
		(drill 0.3302)
		(layers "F.Cu" "B.Cu")
		(tenting
			(front yes)
			(back yes)
		)
		(net "GND")
	)
	(via
		(at 131.34343 100.169615)
		(size 0.55)
		(drill 0.3)
		(layers "F.Cu" "B.Cu")
		(tenting
			(front yes)
			(back yes)
		)
		(net "GND")
	)
	(via
		(at 124.41448 101.656615)
		(size 0.55)
		(drill 0.3)
		(layers "F.Cu" "B.Cu")
		(tenting
			(front yes)
			(back yes)
		)
		(net "GND")
	)
	(via
		(at 162.9591 100.396095)
		(size 0.5588)
		(drill 0.3302)
		(layers "F.Cu" "B.Cu")
		(tenting
			(front yes)
			(back yes)
		)
		(net "GND")
	)
	(via
		(at 140.0991 105.476095)
		(size 0.5588)
		(drill 0.3302)
		(layers "F.Cu" "B.Cu")
		(tenting
			(front yes)
			(back yes)
		)
		(net "GND")
	)
	(via
		(at 165.4991 105.476095)
		(size 0.5588)
		(drill 0.3302)
		(layers "F.Cu" "B.Cu")
		(tenting
			(front yes)
			(back yes)
		)
		(net "GND")
	)
	(via
		(at 135.0191 97.856095)
		(size 0.5588)
		(drill 0.3302)
		(layers "F.Cu" "B.Cu")
		(tenting
			(front yes)
			(back yes)
		)
		(net "GND")
	)
	(via
		(at 122.3191 97.856095)
		(size 0.5588)
		(drill 0.3302)
		(layers "F.Cu" "B.Cu")
		(tenting
			(front yes)
			(back yes)
		)
		(net "GND")
	)
	(via
		(at 175.6591 92.776095)
		(size 0.5588)
		(drill 0.3302)
		(layers "F.Cu" "B.Cu")
		(tenting
			(front yes)
			(back yes)
		)
		(net "GND")
	)
	(via
		(at 132.4791 92.776095)
		(size 0.5588)
		(drill 0.3302)
		(layers "F.Cu" "B.Cu")
		(tenting
			(front yes)
			(back yes)
		)
		(net "GND")
	)
	(via
		(at 132.40593 97.465115)
		(size 0.55)
		(drill 0.3)
		(layers "F.Cu" "B.Cu")
		(tenting
			(front yes)
			(back yes)
		)
		(net "GND")
	)
	(via
		(at 124.0415 100.495555)
		(size 0.55)
		(drill 0.3)
		(layers "F.Cu" "B.Cu")
		(tenting
			(front yes)
			(back yes)
		)
		(net "GND")
	)
	(via
		(at 133.9311 95.998985)
		(size 0.55)
		(drill 0.3)
		(layers "F.Cu" "B.Cu")
		(tenting
			(front yes)
			(back yes)
		)
		(net "GND")
	)
	(via
		(at 124.8591 115.636095)
		(size 0.5588)
		(drill 0.3302)
		(layers "F.Cu" "B.Cu")
		(tenting
			(front yes)
			(back yes)
		)
		(net "GND")
	)
	(via
		(at 142.6391 102.936095)
		(size 0.5588)
		(drill 0.3302)
		(layers "F.Cu" "B.Cu")
		(tenting
			(front yes)
			(back yes)
		)
		(net "GND")
	)
	(via
		(at 119.7791 108.016095)
		(size 0.5588)
		(drill 0.3302)
		(layers "F.Cu" "B.Cu")
		(tenting
			(front yes)
			(back yes)
		)
		(net "GND")
	)
	(via
		(at 119.40483 100.691155)
		(size 0.55)
		(drill 0.3)
		(layers "F.Cu" "B.Cu")
		(tenting
			(front yes)
			(back yes)
		)
		(net "GND")
	)
	(via
		(at 122.3191 113.096095)
		(size 0.5588)
		(drill 0.3302)
		(layers "F.Cu" "B.Cu")
		(tenting
			(front yes)
			(back yes)
		)
		(net "GND")
	)
	(via
		(at 135.0191 105.476095)
		(size 0.5588)
		(drill 0.3302)
		(layers "F.Cu" "B.Cu")
		(tenting
			(front yes)
			(back yes)
		)
		(net "GND")
	)
	(via
		(at 133.58778 97.925255)
		(size 0.55)
		(drill 0.3)
		(layers "F.Cu" "B.Cu")
		(tenting
			(front yes)
			(back yes)
		)
		(net "GND")
	)
	(via
		(at 152.7991 102.936095)
		(size 0.5588)
		(drill 0.3302)
		(layers "F.Cu" "B.Cu")
		(tenting
			(front yes)
			(back yes)
		)
		(net "GND")
	)
	(via
		(at 137.5591 97.856095)
		(size 0.5588)
		(drill 0.3302)
		(layers "F.Cu" "B.Cu")
		(tenting
			(front yes)
			(back yes)
		)
		(net "GND")
	)
	(via
		(at 147.7191 108.016095)
		(size 0.5588)
		(drill 0.3302)
		(layers "F.Cu" "B.Cu")
		(tenting
			(front yes)
			(back yes)
		)
		(net "GND")
	)
	(via
		(at 126.15607 100.440665)
		(size 0.55)
		(drill 0.3)
		(layers "F.Cu" "B.Cu")
		(tenting
			(front yes)
			(back yes)
		)
		(net "GND")
	)
	(via
		(at 138.4146 96.556625)
		(size 0.55)
		(drill 0.3)
		(layers "F.Cu" "B.Cu")
		(tenting
			(front yes)
			(back yes)
		)
		(net "GND")
	)
	(via
		(at 135.0191 102.936095)
		(size 0.5588)
		(drill 0.3302)
		(layers "F.Cu" "B.Cu")
		(tenting
			(front yes)
			(back yes)
		)
		(net "GND")
	)
	(via
		(at 152.7991 92.776095)
		(size 0.5588)
		(drill 0.3302)
		(layers "F.Cu" "B.Cu")
		(tenting
			(front yes)
			(back yes)
		)
		(net "GND")
	)
	(via
		(at 138.04416 95.395565)
		(size 0.55)
		(drill 0.3)
		(layers "F.Cu" "B.Cu")
		(tenting
			(front yes)
			(back yes)
		)
		(net "GND")
	)
	(via
		(at 168.0391 95.316095)
		(size 0.5588)
		(drill 0.3302)
		(layers "F.Cu" "B.Cu")
		(tenting
			(front yes)
			(back yes)
		)
		(net "GND")
	)
	(via
		(at 135.0191 92.776095)
		(size 0.5588)
		(drill 0.3302)
		(layers "F.Cu" "B.Cu")
		(tenting
			(front yes)
			(back yes)
		)
		(net "GND")
	)
	(via
		(at 150.2591 95.316095)
		(size 0.5588)
		(drill 0.3302)
		(layers "F.Cu" "B.Cu")
		(tenting
			(front yes)
			(back yes)
		)
		(net "GND")
	)
	(via
		(at 124.8591 113.096095)
		(size 0.5588)
		(drill 0.3302)
		(layers "F.Cu" "B.Cu")
		(tenting
			(front yes)
			(back yes)
		)
		(net "GND")
	)
	(via
		(at 173.1191 115.636095)
		(size 0.5588)
		(drill 0.3302)
		(layers "F.Cu" "B.Cu")
		(tenting
			(front yes)
			(back yes)
		)
		(net "GND")
	)
	(via
		(at 137.5591 110.556095)
		(size 0.5588)
		(drill 0.3302)
		(layers "F.Cu" "B.Cu")
		(tenting
			(front yes)
			(back yes)
		)
		(net "GND")
	)
	(via
		(at 129.9391 115.636095)
		(size 0.5588)
		(drill 0.3302)
		(layers "F.Cu" "B.Cu")
		(tenting
			(front yes)
			(back yes)
		)
		(net "GND")
	)
	(via
		(at 142.6391 92.776095)
		(size 0.5588)
		(drill 0.3302)
		(layers "F.Cu" "B.Cu")
		(tenting
			(front yes)
			(back yes)
		)
		(net "GND")
	)
	(via
		(at 140.0991 92.776095)
		(size 0.5588)
		(drill 0.3302)
		(layers "F.Cu" "B.Cu")
		(tenting
			(front yes)
			(back yes)
		)
		(net "GND")
	)
	(via
		(at 123.35648 101.656615)
		(size 0.55)
		(drill 0.3)
		(layers "F.Cu" "B.Cu")
		(tenting
			(front yes)
			(back yes)
		)
		(net "GND")
	)
	(via
		(at 122.3191 95.316095)
		(size 0.5588)
		(drill 0.3302)
		(layers "F.Cu" "B.Cu")
		(tenting
			(front yes)
			(back yes)
		)
		(net "GND")
	)
	(via
		(at 119.52597 101.742195)
		(size 0.55)
		(drill 0.3)
		(layers "F.Cu" "B.Cu")
		(tenting
			(front yes)
			(back yes)
		)
		(net "GND")
	)
	(via
		(at 170.5791 92.776095)
		(size 0.5588)
		(drill 0.3302)
		(layers "F.Cu" "B.Cu")
		(tenting
			(front yes)
			(back yes)
		)
		(net "GND")
	)
	(via
		(at 160.4191 115.636095)
		(size 0.5588)
		(drill 0.3302)
		(layers "F.Cu" "B.Cu")
		(tenting
			(front yes)
			(back yes)
		)
		(net "GND")
	)
	(via
		(at 157.8791 115.636095)
		(size 0.5588)
		(drill 0.3302)
		(layers "F.Cu" "B.Cu")
		(tenting
			(front yes)
			(back yes)
		)
		(net "GND")
	)
	(via
		(at 150.2591 115.636095)
		(size 0.5588)
		(drill 0.3302)
		(layers "F.Cu" "B.Cu")
		(tenting
			(front yes)
			(back yes)
		)
		(net "GND")
	)
	(via
		(at 134.3359 97.177135)
		(size 0.55)
		(drill 0.3)
		(layers "F.Cu" "B.Cu")
		(tenting
			(front yes)
			(back yes)
		)
		(net "GND")
	)
	(via
		(at 165.4991 115.636095)
		(size 0.5588)
		(drill 0.3302)
		(layers "F.Cu" "B.Cu")
		(tenting
			(front yes)
			(back yes)
		)
		(net "GND")
	)
	(via
		(at 173.1191 105.476095)
		(size 0.5588)
		(drill 0.3302)
		(layers "F.Cu" "B.Cu")
		(tenting
			(front yes)
			(back yes)
		)
		(net "GND")
	)
	(via
		(at 133.15405 96.716995)
		(size 0.55)
		(drill 0.3)
		(layers "F.Cu" "B.Cu")
		(tenting
			(front yes)
			(back yes)
		)
		(net "GND")
	)
	(via
		(at 157.8791 110.556095)
		(size 0.5588)
		(drill 0.3302)
		(layers "F.Cu" "B.Cu")
		(tenting
			(front yes)
			(back yes)
		)
		(net "GND")
	)
	(via
		(at 157.8791 95.316095)
		(size 0.5588)
		(drill 0.3302)
		(layers "F.Cu" "B.Cu")
		(tenting
			(front yes)
			(back yes)
		)
		(net "GND")
	)
	(via
		(at 129.9391 95.316095)
		(size 0.5588)
		(drill 0.3302)
		(layers "F.Cu" "B.Cu")
		(tenting
			(front yes)
			(back yes)
		)
		(net "GND")
	)
	(via
		(at 132.4791 115.636095)
		(size 0.5588)
		(drill 0.3302)
		(layers "F.Cu" "B.Cu")
		(tenting
			(front yes)
			(back yes)
		)
		(net "GND")
	)
	(via
		(at 165.4991 102.936095)
		(size 0.5588)
		(drill 0.3302)
		(layers "F.Cu" "B.Cu")
		(tenting
			(front yes)
			(back yes)
		)
		(net "GND")
	)
	(via
		(at 130.58326 100.905485)
		(size 0.55)
		(drill 0.3)
		(layers "F.Cu" "B.Cu")
		(tenting
			(front yes)
			(back yes)
		)
		(net "GND")
	)
	(via
		(at 170.9151 106.576095)
		(size 0.55)
		(drill 0.33)
		(layers "F.Cu" "B.Cu")
		(net "GND")
	)
	(via
		(at 125.0995 100.495555)
		(size 0.55)
		(drill 0.3)
		(layers "F.Cu" "B.Cu")
		(tenting
			(front yes)
			(back yes)
		)
		(net "GND")
	)
	(via
		(at 129.9391 97.856095)
		(size 0.5588)
		(drill 0.3302)
		(layers "F.Cu" "B.Cu")
		(tenting
			(front yes)
			(back yes)
		)
		(net "GND")
	)
	(via
		(at 127.3991 105.476095)
		(size 0.5588)
		(drill 0.3302)
		(layers "F.Cu" "B.Cu")
		(tenting
			(front yes)
			(back yes)
		)
		(net "GND")
	)
	(via
		(at 121.41171 102.233675)
		(size 0.55)
		(drill 0.3)
		(layers "F.Cu" "B.Cu")
		(tenting
			(front yes)
			(back yes)
		)
		(net "GND")
	)
	(via
		(at 150.2591 105.476095)
		(size 0.5588)
		(drill 0.3302)
		(layers "F.Cu" "B.Cu")
		(tenting
			(front yes)
			(back yes)
		)
		(net "GND")
	)
	(via
		(at 129.9391 110.556095)
		(size 0.5588)
		(drill 0.3302)
		(layers "F.Cu" "B.Cu")
		(tenting
			(front yes)
			(back yes)
		)
		(net "GND")
	)
	(via
		(at 129.9391 102.936095)
		(size 0.5588)
		(drill 0.3302)
		(layers "F.Cu" "B.Cu")
		(tenting
			(front yes)
			(back yes)
		)
		(net "GND")
	)
	(via
		(at 175.6591 95.316095)
		(size 0.5588)
		(drill 0.3302)
		(layers "F.Cu" "B.Cu")
		(tenting
			(front yes)
			(back yes)
		)
		(net "GND")
	)
	(via
		(at 162.9591 110.556095)
		(size 0.5588)
		(drill 0.3302)
		(layers "F.Cu" "B.Cu")
		(tenting
			(front yes)
			(back yes)
		)
		(net "GND")
	)
	(via
		(at 140.0991 115.636095)
		(size 0.5588)
		(drill 0.3302)
		(layers "F.Cu" "B.Cu")
		(tenting
			(front yes)
			(back yes)
		)
		(net "GND")
	)
	(via
		(at 119.7791 113.096095)
		(size 0.5588)
		(drill 0.3302)
		(layers "F.Cu" "B.Cu")
		(tenting
			(front yes)
			(back yes)
		)
		(net "GND")
	)
	(via
		(at 124.8591 95.316095)
		(size 0.5588)
		(drill 0.3302)
		(layers "F.Cu" "B.Cu")
		(tenting
			(front yes)
			(back yes)
		)
		(net "GND")
	)
	(via
		(at 142.6391 108.016095)
		(size 0.5588)
		(drill 0.3302)
		(layers "F.Cu" "B.Cu")
		(tenting
			(front yes)
			(back yes)
		)
		(net "GND")
	)
	(via
		(at 122.3191 105.476095)
		(size 0.5588)
		(drill 0.3302)
		(layers "F.Cu" "B.Cu")
		(tenting
			(front yes)
			(back yes)
		)
		(net "GND")
	)
	(via
		(at 162.9591 92.776095)
		(size 0.5588)
		(drill 0.3302)
		(layers "F.Cu" "B.Cu")
		(tenting
			(front yes)
			(back yes)
		)
		(net "GND")
	)
	(via
		(at 129.31838 100.348515)
		(size 0.55)
		(drill 0.3)
		(layers "F.Cu" "B.Cu")
		(tenting
			(front yes)
			(back yes)
		)
		(net "GND")
	)
	(via
		(at 140.0991 108.016095)
		(size 0.5588)
		(drill 0.3302)
		(layers "F.Cu" "B.Cu")
		(tenting
			(front yes)
			(back yes)
		)
		(net "GND")
	)
	(via
		(at 170.5791 105.476095)
		(size 0.5588)
		(drill 0.3302)
		(layers "F.Cu" "B.Cu")
		(tenting
			(front yes)
			(back yes)
		)
		(net "GND")
	)
	(via
		(at 122.3191 118.176095)
		(size 0.5588)
		(drill 0.3302)
		(layers "F.Cu" "B.Cu")
		(tenting
			(front yes)
			(back yes)
		)
		(net "GND")
	)
	(via
		(at 127.3991 115.636095)
		(size 0.5588)
		(drill 0.3302)
		(layers "F.Cu" "B.Cu")
		(tenting
			(front yes)
			(back yes)
		)
		(net "GND")
	)
	(arc
		(start 119.063833 99.856975)
		(mid 120.70528 99.031475)
		(end 122.346727 99.856975)
		(width 0.0127)
		(layer "F.Cu")
		(net "GND")
	)
	(arc
		(start 122.346727 102.295375)
		(mid 120.70528 103.120875)
		(end 119.063833 102.295375)
		(width 0.0127)
		(layer "F.Cu")
		(net "GND")
	)
	(segment
		(start 149.31461 99.276285)
		(end 149.31461 97.076585)
		(width 0.254)
		(layer "F.Cu")
		(net "EXTIN")
	)
	(segment
		(start 149.31461 97.161445)
		(end 149.3151 97.160955)
		(width 0.254)
		(layer "F.Cu")
		(net "EXTIN")
	)
	(segment
		(start 152.9921 95.649095)
		(end 153.1151 95.526095)
		(width 0.254)
		(layer "F.Cu")
		(net "D_SEL")
	)
	(segment
		(start 151.5151 97.076095)
		(end 152.9421 95.649095)
		(width 0.254)
		(layer "F.Cu")
		(net "D_SEL")
	)
	(segment
		(start 152.9421 95.649095)
		(end 152.9921 95.649095)
		(width 0.254)
		(layer "F.Cu")
		(net "D_SEL")
	)
	(segment
		(start 151.5151 99.275435)
		(end 151.5151 97.076095)
		(width 0.254)
		(layer "F.Cu")
		(net "D_SEL")
	)
	(segment
		(start 153.1151 95.526095)
		(end 153.1151 95.476095)
		(width 0.254)
		(layer "F.Cu")
		(net "D_SEL")
	)
	(segment
		(start 128.3613 107.122295)
		(end 128.3613 106.986495)
		(width 0.508)
		(layer "F.Cu")
		(net "+5V")
	)
	(segment
		(start 157.26672 117.976095)
		(end 159.0643 116.178515)
		(width 0.508)
		(layer "F.Cu")
		(net "+5V")
	)
	(segment
		(start 128.5611 110.430095)
		(end 130.1151 108.876095)
		(width 0.508)
		(layer "F.Cu")
		(net "+5V")
	)
	(segment
		(start 128.5151 110.476095)
		(end 128.5151 110.434095)
		(width 0.508)
		(layer "F.Cu")
		(net "+5V")
	)
	(segment
		(start 128.5151 110.434095)
		(end 128.5191 110.430095)
		(width 0.508)
		(layer "F.Cu")
		(net "+5V")
	)
	(segment
		(start 139.2151 117.976095)
		(end 157.26672 117.976095)
		(width 0.508)
		(layer "F.Cu")
		(net "+5V")
	)
	(segment
		(start 159.0643 116.178515)
		(end 159.0643 113.560105)
		(width 0.508)
		(layer "F.Cu")
		(net "+5V")
	)
	(segment
		(start 159.0643 113.560105)
		(end 159.0643 111.151495)
		(width 0.508)
		(layer "F.Cu")
		(net "+5V")
	)
	(segment
		(start 175.93669 112.596105)
		(end 178.26011 112.596105)
		(width 0.508)
		(layer "F.Cu")
		(net "+5V")
	)
	(segment
		(start 128.5191 110.430095)
		(end 128.5611 110.430095)
		(width 0.508)
		(layer "F.Cu")
		(net "+5V")
	)
	(segment
		(start 130.1151 108.876095)
		(end 130.1151 108.876095)
		(width 0.508)
		(layer "F.Cu")
		(net "+5V")
	)
	(segment
		(start 175.63911 112.893685)
		(end 175.93669 112.596105)
		(width 0.508)
		(layer "F.Cu")
		(net "+5V")
	)
	(segment
		(start 159.0643 113.560105)
		(end 175.37316 113.560105)
		(width 0.508)
		(layer "F.Cu")
		(net "+5V")
	)
	(segment
		(start 175.37316 113.560105)
		(end 175.63911 113.294155)
		(width 0.508)
		(layer "F.Cu")
		(net "+5V")
	)
	(segment
		(start 130.1651 108.926095)
		(end 139.2151 117.976095)
		(width 0.508)
		(layer "F.Cu")
		(net "+5V")
	)
	(segment
		(start 175.63911 113.294155)
		(end 175.63911 112.893685)
		(width 0.508)
		(layer "F.Cu")
		(net "+5V")
	)
	(segment
		(start 128.3613 107.122295)
		(end 130.1151 108.876095)
		(width 0.508)
		(layer "F.Cu")
		(net "+5V")
	)
	(segment
		(start 167.40889 112.596105)
		(end 173.71011 112.596105)
		(width 0.508)
		(layer "F.Cu")
		(net "+3V3")
	)
	(segment
		(start 153.21407 113.676095)
		(end 158.12207 108.768095)
		(width 0.508)
		(layer "F.Cu")
		(net "+3V3")
	)
	(segment
		(start 163.58088 108.768095)
		(end 165.96429 111.151495)
		(width 0.508)
		(layer "F.Cu")
		(net "+3V3")
	)
	(segment
		(start 158.12207 108.768095)
		(end 163.58088 108.768095)
		(width 0.508)
		(layer "F.Cu")
		(net "+3V3")
	)
	(segment
		(start 165.96429 111.151495)
		(end 167.40889 112.596105)
		(width 0.508)
		(layer "F.Cu")
		(net "+3V3")
	)
	(zone
		(layer "F.Cu")
		(hatch edge 0.5)
		(connect_pads
			(clearance 0)
		)
		(min_thickness 0.25)
		(keepout
			(tracks allowed)
			(vias allowed)
			(pads allowed)
			(copperpour not_allowed)
			(footprints allowed)
		)
		(placement
			(enabled no)
			(sheetname "")
		)
		(fill
			(thermal_gap 0.5)
			(thermal_bridge_width 0.5)
			(island_removal_mode 0)
		)
		(polygon
			(pts
				(xy 140.042 95.542485) (xy 140.10648 95.585575) (xy 140.14956 95.650045) (xy 140.16469 95.726095)
				(xy 140.16469 96.226095) (xy 140.14956 96.302155) (xy 140.10648 96.366625) (xy 140.042 96.409705)
				(xy 139.96595 96.424835) (xy 139.46595 96.424835) (xy 139.3899 96.409705) (xy 139.32542 96.366625)
				(xy 139.28234 96.302155) (xy 139.27616 96.271065) (xy 135.76805 96.271065) (xy 135.74968 96.267405)
				(xy 135.329 96.308835) (xy 134.90682 96.436905) (xy 134.51774 96.644875) (xy 134.19097 96.913045)
				(xy 134.18057 96.928615) (xy 130.57133 100.537855) (xy 130.56905 100.541275) (xy 130.56248 100.545655)
				(xy 130.55759 100.551865) (xy 130.24294 100.820605) (xy 130.22924 100.828275) (xy 130.21771 100.838935)
				(xy 129.86488 101.055145) (xy 129.85015 101.060575) (xy 129.8371 101.069305) (xy 129.4548 101.227655)
				(xy 129.4394 101.230715) (xy 129.42514 101.237295) (xy 129.02278 101.333895) (xy 129.00709 101.334505)
				(xy 128.99197 101.338765) (xy 128.57945 101.371235) (xy 128.57161 101.370305) (xy 128.56386 101.371845)
				(xy 128.55982 101.371045) (xy 126.12374 101.371045) (xy 126.09329 101.416625) (xy 126.02881 101.459705)
				(xy 125.95276 101.474825) (xy 125.45276 101.474825) (xy 125.37671 101.459705) (xy 125.31223 101.416625)
				(xy 125.28178 101.371045) (xy 121.73809 101.371045) (xy 121.73644 101.379325) (xy 121.64879 101.590955)
				(xy 121.63435 101.612565) (xy 121.62285 101.635885) (xy 121.4834 101.817615) (xy 121.46385 101.834755)
				(xy 121.44671 101.854305) (xy 121.26499 101.993745) (xy 121.24167 102.005245) (xy 121.22006 102.019685)
				(xy 121.00843 102.107345) (xy 120.98294 102.112415) (xy 120.95832 102.120765) (xy 120.73122 102.150665)
				(xy 120.70528 102.148965) (xy 120.67934 102.150665) (xy 120.45224 102.120765) (xy 120.42762 102.112415)
				(xy 120.40212 102.107345) (xy 120.1905 102.019685) (xy 120.16888 102.005245) (xy 120.14557 101.993745)
				(xy 119.96384 101.854305) (xy 119.9467 101.834755) (xy 119.92715 101.817615) (xy 119.78771 101.635885)
				(xy 119.77621 101.612575) (xy 119.76177 101.590955) (xy 119.67411 101.379325) (xy 119.66904 101.353835)
				(xy 119.66068 101.329215) (xy 119.63078 101.102115) (xy 119.63248 101.076175) (xy 119.63078 101.050235)
				(xy 119.66068 100.823135) (xy 119.66904 100.798515) (xy 119.67411 100.773025) (xy 119.76177 100.561395)
				(xy 119.77621 100.539785) (xy 119.78771 100.516465) (xy 119.92715 100.334735) (xy 119.9467 100.317595)
				(xy 119.96384 100.298045) (xy 120.14557 100.158605) (xy 120.16888 100.147105) (xy 120.1905 100.132665)
				(xy 120.40212 100.045005) (xy 120.42761 100.039935) (xy 120.45224 100.031575) (xy 120.67934 100.001685)
				(xy 120.70528 100.003385) (xy 120.73122 100.001685) (xy 120.95832 100.031575) (xy 120.98294 100.039935)
				(xy 121.00843 100.045005) (xy 121.22006 100.132665) (xy 121.24167 100.147105) (xy 121.26499 100.158605)
				(xy 121.44672 100.298045) (xy 121.46386 100.317595) (xy 121.4834 100.334735) (xy 121.62285 100.516465)
				(xy 121.63434 100.539775) (xy 121.64879 100.561395) (xy 121.73644 100.773025) (xy 121.73806 100.781125)
				(xy 125.28179 100.781125) (xy 125.31223 100.735565) (xy 125.37671 100.692485) (xy 125.45276 100.677355)
				(xy 125.95276 100.677355) (xy 126.02881 100.692485) (xy 126.09329 100.735565) (xy 126.12373 100.781125)
				(xy 128.56386 100.781125) (xy 128.58223 100.784775) (xy 129.0029 100.743345) (xy 129.42509 100.615275)
				(xy 129.81417 100.407305) (xy 130.14094 100.139135) (xy 130.15134 100.123565) (xy 133.76058 96.514325)
				(xy 133.76286 96.510915) (xy 133.76943 96.506525) (xy 133.77432 96.500315) (xy 134.08897 96.231575)
				(xy 134.10267 96.223905) (xy 134.1142 96.213245) (xy 134.46702 95.997035) (xy 134.48176 95.991605)
				(xy 134.49481 95.982885) (xy 134.87711 95.824525) (xy 134.89251 95.821465) (xy 134.90677 95.814885)
				(xy 135.30913 95.718295) (xy 135.32482 95.717675) (xy 135.33994 95.713415) (xy 135.75246 95.680945)
				(xy 135.7603 95.681875) (xy 135.76805 95.680335) (xy 135.77209 95.681135) (xy 139.27616 95.681135)
				(xy 139.28234 95.650045) (xy 139.32542 95.585575) (xy 139.3899 95.542485) (xy 139.46595 95.527365)
				(xy 139.96595 95.527365)
			)
		)
	)
	(zone
		(net "+3V3")
		(layer "F.Cu")
		(hatch edge 0.5)
		(priority 3)
		(connect_pads
			(clearance 0.5)
		)
		(min_thickness 0.25)
		(fill yes
			(thermal_gap 0.254)
			(thermal_bridge_width 0.254)
			(island_removal_mode 0)
		)
		(polygon
			(pts
				(xy 151.9151 110.576095) (xy 151.9151 112.876095) (xy 153.6151 112.876095) (xy 153.6151 113.976095)
				(xy 149.8151 113.976095) (xy 149.8151 110.576095) (xy 150.1151 110.576095)
			)
		)
	)
	(zone
		(net "GND")
		(layer "F.Cu")
		(hatch edge 0.5)
		(connect_pads
			(clearance 0.5)
		)
		(min_thickness 0.25)
		(fill yes
			(thermal_gap 0.254)
			(thermal_bridge_width 0.254)
			(island_removal_mode 0)
		)
		(polygon
			(pts
				(arc
					(start 115.9601 120.876095)
					(mid 115.221173 120.570021)
					(end 114.9151 119.831094)
				)
				(xy 114.9151 119.831095)
				(arc
					(start 114.9131 90.200096)
					(mid 115.226434 89.443139)
					(end 115.983097 89.129095)
				)
				(xy 115.9831 89.129095)
				(arc
					(start 181.0091 89.127095)
					(mid 181.772421 89.443066)
					(end 182.0891 90.206094)
				)
				(xy 182.0891 90.206095)
				(arc
					(start 182.0861 119.861092)
					(mid 181.787995 120.581283)
					(end 181.068096 120.880095)
				)
				(xy 181.0681 120.880095)
			)
		)
	)
	(zone
		(layers "F.Cu" "B.Cu" "In1.Cu" "In2.Cu")
		(hatch edge 0.5)
		(connect_pads
			(clearance 0)
		)
		(min_thickness 0.25)
		(keepout
			(tracks not_allowed)
			(vias not_allowed)
			(pads not_allowed)
			(copperpour not_allowed)
			(footprints allowed)
		)
		(placement
			(enabled no)
			(sheetname "")
		)
		(fill
			(thermal_gap 0.5)
			(thermal_bridge_width 0.5)
			(island_removal_mode 0)
		)
		(polygon
			(pts
				(xy 115.960101 120.869745) (xy 115.963833 120.870958) (xy 115.96614 120.874133) (xy 115.96614 120.878057)
				(xy 115.963833 120.881232) (xy 115.960101 120.882445) (xy 115.777536 120.866473) (xy 115.600517 120.819041)
				(xy 115.434425 120.741591) (xy 115.284305 120.636476) (xy 115.154719 120.50689) (xy 115.049604 120.35677)
				(xy 114.972154 120.190678) (xy 114.924722 120.013659) (xy 114.90875 119.831094) (xy 114.909963 119.827362)
				(xy 114.913138 119.825055) (xy 114.917062 119.825055) (xy 114.920237 119.827362) (xy 114.92145 119.831094)
				(xy 114.92145 119.921964) (xy 114.953009 120.100944) (xy 115.015168 120.271724) (xy 115.106038 120.429116)
				(xy 115.222858 120.568337) (xy 115.362079 120.685157) (xy 115.519471 120.776027) (xy 115.690251 120.838186)
				(xy 115.869231 120.869745) (xy 115.960101 120.869745)
			)
		)
	)
	(zone
		(layers "F.Cu" "B.Cu" "In1.Cu" "In2.Cu")
		(hatch edge 0.5)
		(connect_pads
			(clearance 0)
		)
		(min_thickness 0.25)
		(keepout
			(tracks not_allowed)
			(vias not_allowed)
			(pads not_allowed)
			(copperpour not_allowed)
			(footprints allowed)
		)
		(placement
			(enabled no)
			(sheetname "")
		)
		(fill
			(thermal_gap 0.5)
			(thermal_bridge_width 0.5)
			(island_removal_mode 0)
		)
		(polygon
			(pts
				(xy 114.91945 90.200095) (xy 114.918237 90.203827) (xy 114.915062 90.206134) (xy 114.911138 90.206134)
				(xy 114.907963 90.203827) (xy 114.90675 90.200095) (xy 114.923098 90.013125) (xy 114.971646 89.83183)
				(xy 115.05092 89.66171) (xy 115.158515 89.50793) (xy 115.291165 89.375156) (xy 115.444844 89.267418)
				(xy 115.614889 89.187985) (xy 115.79614 89.139268) (xy 115.983094 89.122745) (xy 115.986828 89.123954)
				(xy 115.989137 89.127127) (xy 115.989141 89.131052) (xy 115.986837 89.134229) (xy 115.983106 89.135445)
				(xy 115.890016 89.135527) (xy 115.706692 89.168009) (xy 115.531788 89.231813) (xy 115.37061 89.325003)
				(xy 115.22805 89.444751) (xy 115.108436 89.587422) (xy 115.015396 89.748687) (xy 114.951756 89.923651)
				(xy 114.919445 90.107005) (xy 114.91945 90.200095)
			)
		)
	)
	(zone
		(layers "F.Cu" "B.Cu" "In1.Cu" "In2.Cu")
		(hatch edge 0.5)
		(connect_pads
			(clearance 0)
		)
		(min_thickness 0.25)
		(keepout
			(tracks not_allowed)
			(vias not_allowed)
			(pads not_allowed)
			(copperpour not_allowed)
			(footprints allowed)
		)
		(placement
			(enabled no)
			(sheetname "")
		)
		(fill
			(thermal_gap 0.5)
			(thermal_bridge_width 0.5)
			(island_removal_mode 0)
		)
		(polygon
			(pts
				(xy 181.07053 120.874228) (xy 181.073967 120.877665) (xy 181.073967 120.882525) (xy 181.07053 120.885962)
				(xy 181.068099 120.886445) (xy 115.9601 120.882445) (xy 115.95767 120.881962) (xy 115.954233 120.878525)
				(xy 115.954233 120.873665) (xy 115.95767 120.870228) (xy 115.9601 120.869745) (xy 181.0681 120.873745)
			)
		)
	)
	(zone
		(layers "F.Cu" "B.Cu" "In1.Cu" "In2.Cu")
		(hatch edge 0.5)
		(connect_pads
			(clearance 0)
		)
		(min_thickness 0.25)
		(keepout
			(tracks not_allowed)
			(vias not_allowed)
			(pads not_allowed)
			(copperpour not_allowed)
			(footprints allowed)
		)
		(placement
			(enabled no)
			(sheetname "")
		)
		(fill
			(thermal_gap 0.5)
			(thermal_bridge_width 0.5)
			(island_removal_mode 0)
		)
		(polygon
			(pts
				(xy 181.01153 89.121228) (xy 181.014967 89.124665) (xy 181.014967 89.129525) (xy 181.01153 89.132962)
				(xy 181.0091 89.133445) (xy 115.9831 89.135445) (xy 115.98067 89.134962) (xy 115.977233 89.131525)
				(xy 115.977233 89.126665) (xy 115.98067 89.123228) (xy 115.9831 89.122745) (xy 181.0091 89.120745)
			)
		)
	)
	(zone
		(layers "F.Cu" "B.Cu" "In1.Cu" "In2.Cu")
		(hatch edge 0.5)
		(connect_pads
			(clearance 0)
		)
		(min_thickness 0.25)
		(keepout
			(tracks not_allowed)
			(vias not_allowed)
			(pads not_allowed)
			(copperpour not_allowed)
			(footprints allowed)
		)
		(placement
			(enabled no)
			(sheetname "")
		)
		(fill
			(thermal_gap 0.5)
			(thermal_bridge_width 0.5)
			(island_removal_mode 0)
		)
		(polygon
			(pts
				(xy 114.920967 119.833525) (xy 114.91753 119.836962) (xy 114.91267 119.836962) (xy 114.909233 119.833525)
				(xy 114.90875 119.831095) (xy 114.90675 90.200095) (xy 114.907233 90.197665) (xy 114.91067 90.194228)
				(xy 114.91553 90.194228) (xy 114.918967 90.197665) (xy 114.91945 90.200095) (xy 114.92145 119.831095)
			)
		)
	)
	(zone
		(layers "F.Cu" "B.Cu" "In1.Cu" "In2.Cu")
		(hatch edge 0.5)
		(connect_pads
			(clearance 0)
		)
		(min_thickness 0.25)
		(keepout
			(tracks not_allowed)
			(vias not_allowed)
			(pads not_allowed)
			(copperpour not_allowed)
			(footprints allowed)
		)
		(placement
			(enabled no)
			(sheetname "")
		)
		(fill
			(thermal_gap 0.5)
			(thermal_bridge_width 0.5)
			(island_removal_mode 0)
		)
		(polygon
			(pts
				(xy 182.083233 90.203665) (xy 182.086671 90.200228) (xy 182.091531 90.200228) (xy 182.094967 90.203666)
				(xy 182.09545 90.206096) (xy 182.09245 119.861096) (xy 182.091967 119.863526) (xy 182.088529 119.866962)
				(xy 182.083669 119.866962) (xy 182.080233 119.863524) (xy 182.07975 119.861094) (xy 182.08275 90.206095)
			)
		)
	)
	(zone
		(layers "F.Cu" "B.Cu" "In1.Cu" "In2.Cu")
		(hatch edge 0.5)
		(connect_pads
			(clearance 0)
		)
		(min_thickness 0.25)
		(keepout
			(tracks not_allowed)
			(vias not_allowed)
			(pads not_allowed)
			(copperpour not_allowed)
			(footprints allowed)
		)
		(placement
			(enabled no)
			(sheetname "")
		)
		(fill
			(thermal_gap 0.5)
			(thermal_bridge_width 0.5)
			(island_removal_mode 0)
		)
		(polygon
			(pts
				(xy 182.07975 119.861095) (xy 182.080963 119.857363) (xy 182.084138 119.855056) (xy 182.088062 119.855056)
				(xy 182.091237 119.857363) (xy 182.09245 119.861095) (xy 182.076892 120.039035) (xy 182.030691 120.211575)
				(xy 181.955247 120.373479) (xy 181.852852 120.519835) (xy 181.726611 120.646199) (xy 181.580357 120.748739)
				(xy 181.418527 120.824341) (xy 181.246032 120.870712) (xy 181.068107 120.886445) (xy 181.064374 120.885236)
				(xy 181.062064 120.882063) (xy 181.06206 120.878139) (xy 181.064364 120.874961) (xy 181.068095 120.873745)
				(xy 181.156635 120.873663) (xy 181.330998 120.842761) (xy 181.497353 120.782069) (xy 181.650651 120.693428)
				(xy 181.78624 120.579529) (xy 181.900006 120.443828) (xy 181.988496 120.290443) (xy 182.049024 120.124029)
				(xy 182.079755 119.949635) (xy 182.07975 119.861095)
			)
		)
	)
	(zone
		(layers "F.Cu" "B.Cu" "In1.Cu" "In2.Cu")
		(hatch edge 0.5)
		(connect_pads
			(clearance 0)
		)
		(min_thickness 0.25)
		(keepout
			(tracks not_allowed)
			(vias not_allowed)
			(pads not_allowed)
			(copperpour not_allowed)
			(footprints allowed)
		)
		(placement
			(enabled no)
			(sheetname "")
		)
		(fill
			(thermal_gap 0.5)
			(thermal_bridge_width 0.5)
			(island_removal_mode 0)
		)
		(polygon
			(pts
				(xy 181.0091 89.133445) (xy 181.005368 89.132232) (xy 181.003061 89.129057) (xy 181.003061 89.125133)
				(xy 181.005368 89.121958) (xy 181.0091 89.120745) (xy 181.197632 89.13723) (xy 181.380443 89.186184)
				(xy 181.551984 89.266121) (xy 181.707049 89.374615) (xy 181.840933 89.508375) (xy 181.949571 89.663339)
				(xy 182.029667 89.834806) (xy 182.07879 90.017571) (xy 182.09545 90.206088) (xy 182.094241 90.209822)
				(xy 182.091068 90.212131) (xy 182.087143 90.212135) (xy 182.083966 90.209831) (xy 182.08275 90.2061)
				(xy 182.082668 90.112223) (xy 182.049912 89.927349) (xy 181.985569 89.750964) (xy 181.891592 89.588423)
				(xy 181.770832 89.444657) (xy 181.626954 89.324031) (xy 181.464326 89.230204) (xy 181.287882 89.166025)
				(xy 181.102977 89.13344) (xy 181.0091 89.133445)
			)
		)
	)
	(zone
		(layer "F.Mask")
		(hatch edge 0.5)
		(priority 5)
		(connect_pads
			(clearance 0.5)
		)
		(min_thickness 0.25)
		(fill yes
			(thermal_gap 0.254)
			(thermal_bridge_width 0.254)
			(island_removal_mode 0)
		)
		(polygon
			(pts
				(arc
					(start 115.9811 120.580085)
					(mid 115.452847 120.368759)
					(end 115.216105 119.851398)
				)
				(xy 115.2161 119.851405) (xy 115.2161 114.010095)
				(arc
					(start 120.416099 114.010095)
					(mid 121.337486 114.376301)
					(end 121.756097 115.275092)
				)
				(xy 121.7561 115.275095) (xy 121.7561 120.580095) (xy 115.9811 120.580095)
			)
		)
	)
	(zone
		(layer "F.Mask")
		(hatch edge 0.5)
		(priority 5)
		(connect_pads
			(clearance 0.5)
		)
		(min_thickness 0.25)
		(fill yes
			(thermal_gap 0.254)
			(thermal_bridge_width 0.254)
			(island_removal_mode 0)
		)
		(polygon
			(pts
				(arc
					(start 174.256455 94.19446)
					(mid 174.837762 95.476915)
					(end 176.144459 96.001465)
				)
				(xy 176.14446 96.001465) (xy 181.78647 96.001465)
				(arc
					(start 181.786465 90.124662)
					(mid 181.538897 89.630642)
					(end 181.023461 89.431465)
				)
				(xy 181.02347 89.431465) (xy 174.25647 89.431465) (xy 174.25646 94.194465)
			)
		)
	)
	(zone
		(layer "F.Mask")
		(hatch edge 0.5)
		(priority 5)
		(connect_pads
			(clearance 0.5)
		)
		(min_thickness 0.25)
		(fill yes
			(thermal_gap 0.254)
			(thermal_bridge_width 0.254)
			(island_removal_mode 0)
		)
		(polygon
			(pts
				(xy 174.2561 120.580095)
				(arc
					(start 174.256098 115.685097)
					(mid 174.804459 114.495502)
					(end 176.0211 114.010095)
				)
				(xy 181.7861 114.010095)
				(arc
					(start 181.7861 119.871784)
					(mid 181.539849 120.376033)
					(end 181.017101 120.580095)
				)
				(xy 181.0171 120.580095)
			)
		)
	)
	(zone
		(layer "F.Mask")
		(hatch edge 0.5)
		(priority 5)
		(connect_pads
			(clearance 0.5)
		)
		(min_thickness 0.25)
		(fill yes
			(thermal_gap 0.254)
			(thermal_bridge_width 0.254)
			(island_removal_mode 0)
		)
		(polygon
			(pts
				(xy 115.2151 96.000095)
				(arc
					(start 115.2151 90.191237)
					(mid 115.438588 89.652976)
					(end 115.977101 89.430095)
				)
				(xy 115.9771 89.430095) (xy 121.7551 89.430095)
				(arc
					(start 121.755091 93.895096)
					(mid 120.993862 95.396015)
					(end 119.423093 96.000095)
				)
				(xy 119.4231 96.000095)
			)
		)
	)
	(zone
		(net "GND")
		(layer "B.Cu")
		(hatch edge 0.5)
		(priority 4)
		(connect_pads
			(clearance 0.5)
		)
		(min_thickness 0.25)
		(fill yes
			(thermal_gap 0.254)
			(thermal_bridge_width 0.254)
			(island_removal_mode 0)
		)
		(polygon
			(pts
				(arc
					(start 115.9601 120.876095)
					(mid 115.221173 120.570021)
					(end 114.9151 119.831094)
				)
				(xy 114.9151 119.831095)
				(arc
					(start 114.9131 90.200096)
					(mid 115.226434 89.443139)
					(end 115.983097 89.129095)
				)
				(xy 115.9831 89.129095)
				(arc
					(start 181.0091 89.127095)
					(mid 181.772421 89.443066)
					(end 182.0891 90.206094)
				)
				(xy 182.0891 90.206095)
				(arc
					(start 182.0861 119.861092)
					(mid 181.787995 120.581283)
					(end 181.068096 120.880095)
				)
				(xy 181.0681 120.880095)
			)
		)
	)
	(zone
		(layer "B.Mask")
		(hatch edge 0.5)
		(priority 5)
		(connect_pads
			(clearance 0.5)
		)
		(min_thickness 0.25)
		(fill yes
			(thermal_gap 0.254)
			(thermal_bridge_width 0.254)
			(island_removal_mode 0)
		)
		(polygon
			(pts
				(xy 174.2561 120.580095)
				(arc
					(start 174.256098 115.685097)
					(mid 174.804459 114.495502)
					(end 176.0211 114.010095)
				)
				(xy 181.7861 114.010095)
				(arc
					(start 181.7861 119.871784)
					(mid 181.539849 120.376033)
					(end 181.017101 120.580095)
				)
				(xy 181.0171 120.580095)
			)
		)
	)
	(zone
		(layer "B.Mask")
		(hatch edge 0.5)
		(priority 5)
		(connect_pads
			(clearance 0.5)
		)
		(min_thickness 0.25)
		(fill yes
			(thermal_gap 0.254)
			(thermal_bridge_width 0.254)
			(island_removal_mode 0)
		)
		(polygon
			(pts
				(xy 115.21173 95.997365)
				(arc
					(start 115.21173 90.188507)
					(mid 115.435218 89.650246)
					(end 115.973731 89.427365)
				)
				(xy 115.97373 89.427365) (xy 121.75173 89.427365)
				(arc
					(start 121.751731 93.892366)
					(mid 120.990502 95.393285)
					(end 119.419733 95.997365)
				)
				(xy 119.41973 95.997365)
			)
		)
	)
	(zone
		(layer "B.Mask")
		(hatch edge 0.5)
		(priority 5)
		(connect_pads
			(clearance 0.5)
		)
		(min_thickness 0.25)
		(fill yes
			(thermal_gap 0.254)
			(thermal_bridge_width 0.254)
			(island_removal_mode 0)
		)
		(polygon
			(pts
				(arc
					(start 174.256095 94.19309)
					(mid 174.837402 95.475545)
					(end 176.144099 96.000095)
				)
				(xy 176.1441 96.000095) (xy 181.7861 96.000095)
				(arc
					(start 181.786105 90.123292)
					(mid 181.538537 89.629272)
					(end 181.023101 89.430095)
				)
				(xy 181.0231 89.430095) (xy 174.2561 89.430095) (xy 174.2561 94.193095)
			)
		)
	)
	(zone
		(layer "B.Mask")
		(hatch edge 0.5)
		(priority 5)
		(connect_pads
			(clearance 0.5)
		)
		(min_thickness 0.25)
		(fill yes
			(thermal_gap 0.254)
			(thermal_bridge_width 0.254)
			(island_removal_mode 0)
		)
		(polygon
			(pts
				(arc
					(start 115.9811 120.580085)
					(mid 115.452847 120.368759)
					(end 115.216105 119.851398)
				)
				(xy 115.2161 119.851395) (xy 115.2161 114.010095)
				(arc
					(start 120.416099 114.010095)
					(mid 121.337486 114.376301)
					(end 121.756097 115.275092)
				)
				(xy 121.7561 115.275085) (xy 121.7561 120.580095) (xy 115.9811 120.580095)
			)
		)
	)
	(zone
		(net "GND")
		(layer "In1.Cu")
		(hatch edge 0.5)
		(priority 5)
		(connect_pads
			(clearance 0.5)
		)
		(min_thickness 0.25)
		(fill yes
			(thermal_gap 0.254)
			(thermal_bridge_width 0.254)
			(island_removal_mode 0)
		)
		(polygon
			(pts
				(arc
					(start 114.9151 119.831095)
					(mid 115.221174 120.570022)
					(end 115.960101 120.876095)
				)
				(xy 115.9601 120.876095)
				(arc
					(start 181.0681 120.880095)
					(mid 181.787996 120.581283)
					(end 182.0861 119.861095)
				)
				(arc
					(start 182.08911 90.206098)
					(mid 181.772432 89.443066)
					(end 181.009106 89.127095)
				)
				(xy 181.0091 89.127095)
				(arc
					(start 115.983105 89.129085)
					(mid 115.226435 89.443126)
					(end 114.9131 90.200089)
				)
				(xy 114.9131 90.200095)
			)
		)
	)
	(zone
		(net "GND")
		(layer "In2.Cu")
		(hatch edge 0.5)
		(priority 1)
		(connect_pads
			(clearance 0.5)
		)
		(min_thickness 0.25)
		(fill yes
			(thermal_gap 0.254)
			(thermal_bridge_width 0.254)
			(island_removal_mode 0)
		)
		(polygon
			(pts
				(arc
					(start 115.9601 120.876095)
					(mid 115.221173 120.570021)
					(end 114.9151 119.831094)
				)
				(xy 114.9151 119.831095)
				(arc
					(start 114.9131 90.200096)
					(mid 115.226434 89.443139)
					(end 115.983097 89.129095)
				)
				(xy 115.9831 89.129095)
				(arc
					(start 181.0091 89.127095)
					(mid 181.772421 89.443066)
					(end 182.0891 90.206094)
				)
				(xy 182.0891 90.206095)
				(arc
					(start 182.0861 119.861092)
					(mid 181.787995 120.581283)
					(end 181.068096 120.880095)
				)
				(xy 181.0681 120.880095)
			)
		)
	)
	(zone
		(layer "User.1")
		(hatch edge 0.5)
		(connect_pads
			(clearance 0)
		)
		(min_thickness 0.25)
		(keepout
			(tracks allowed)
			(vias allowed)
			(pads allowed)
			(copperpour not_allowed)
			(footprints allowed)
		)
		(placement
			(enabled no)
			(sheetname "")
		)
		(fill
			(thermal_gap 0.5)
			(thermal_bridge_width 0.5)
			(island_removal_mode 0)
		)
		(polygon
			(pts
				(arc
					(start 176.7161 117.980095)
					(mid 177.170084 119.076111)
					(end 178.2661 119.530095)
				)
				(arc
					(start 178.2661 119.530095)
					(mid 179.362116 119.076111)
					(end 179.8161 117.980095)
				)
				(arc
					(start 179.8161 117.980095)
					(mid 179.362116 116.884079)
					(end 178.2661 116.430095)
				)
				(arc
					(start 178.2661 116.430095)
					(mid 177.170084 116.884079)
					(end 176.7161 117.980095)
				)
			)
		)
	)
)
